FILE_TYPE = MACRO_DRAWING;
SET COLOR_WIRE YELLOW;
SET COLOR_PROP ORANGE;
SET COLOR_DOT WHITE;
SET COLOR_ARC YELLOW;
SET COLOR_BODY GREEN;
SET COLOR_NOTE PURPLE;
SET PROP_DISPLAY VALUE;
SET PAGE_NUMBER P249;
FORCEADD UNIVERSAL_POWER..1
(-5300 4075);
FORCEPROP 3 LASTPIN (-5300 4025) SIG_NAME P5V_AUX\g
J 0
(-5290 4035);
DISPLAY 0.659574 (-5290 4035);
PAINT MONO (-5290 4035);
DISPLAY INVISIBLE (-5290 4035);
FORCEPROP 1 LAST HDL_POWER P5V_AUX
J 1
(-5300 4125);
DISPLAY 0.617021 (-5300 4125);
PAINT GREEN (-5300 4125);
FORCEPROP 2 LAST CDS_LIB logical_power
J 0
(-5300 4075);
DISPLAY INVISIBLE (-5300 4075);
FORCEPROP 1 LAST PATH I1
J 0
(-5250 4100);
DISPLAY 0.872340 (-5250 4100);
PAINT AQUA (-5250 4100);
DISPLAY INVISIBLE (-5250 4100);
FORCEADD UNIVERSAL_GND..1
(-4850 5800);
FORCEPROP 3 LASTPIN (-4850 5850) SIG_NAME GND\g
J 0
(-4840 5860);
DISPLAY 0.659574 (-4840 5860);
PAINT MONO (-4840 5860);
DISPLAY INVISIBLE (-4840 5860);
FORCEPROP 2 LAST CDS_LIB logical_power
J 0
(-4850 5800);
PAINT MONO (-4850 5800);
DISPLAY INVISIBLE (-4850 5800);
FORCEPROP 1 LAST HDL_POWER GND
J 1
(-4825 5725);
DISPLAY 0.872340 (-4825 5725);
PAINT GREEN (-4825 5725);
DISPLAY INVISIBLE (-4825 5725);
FORCEPROP 1 LAST PATH I10
J 0
(-4775 5800);
DISPLAY 0.872340 (-4775 5800);
PAINT AQUA (-4775 5800);
DISPLAY INVISIBLE (-4775 5800);
FORCEADD Q_RES..1
(-4500 5950);
FORCEPROP 1 LAST PART_NUMBER CS21002FB06
J 0
(-4650 6000);
DISPLAY 0.617021 (-4650 6000);
PAINT BLUE (-4650 6000);
DISPLAY INVISIBLE (-4650 6000);
FORCEPROP 1 LAST PACK_TYPE 0402LF
J 0
(-4650 6050);
DISPLAY 0.617021 (-4650 6050);
PAINT SKYBLUE (-4650 6050);
FORCEPROP 1 LAST MATERIAL EMPTY
J 0
(-4250 5950);
DISPLAY 0.617021 (-4250 5950);
PAINT RED (-4250 5950);
FORCEPROP 1 LAST VALUE 1K
J 2
(-4350 5950);
DISPLAY 0.617021 (-4350 5950);
PAINT SKYBLUE (-4350 5950);
FORCEPROP 1 LAST WATTAGE 1/16W
J 2
(-4300 6050);
DISPLAY 0.617021 (-4300 6050);
PAINT SKYBLUE (-4300 6050);
FORCEPROP 1 LAST TOLERANCE 1%
J 0
(-4325 5950);
DISPLAY 0.617021 (-4325 5950);
PAINT SKYBLUE (-4325 5950);
FORCEPROP 1 LAST LOCATION PR1850
J 0
(-4750 5950);
DISPLAY 0.723404 (-4750 5950);
PAINT AQUA (-4750 5950);
FORCEPROP 1 LASTPIN (-4600 5950) $PN 1
J 0
(-4588 5962);
DISPLAY 0.617021 (-4588 5962);
FORCEPROP 1 LASTPIN (-4400 5950) $PN 2
J 0
(-4438 5962);
DISPLAY 0.617021 (-4438 5962);
FORCEPROP 2 LAST CDS_LIB pure_quanta
J 0
(-4500 5950);
PAINT MONO (-4500 5950);
DISPLAY INVISIBLE (-4500 5950);
FORCEPROP 1 LAST PATH I11
J 0
(-4550 6100);
DISPLAY 0.978723 (-4550 6100);
PAINT WHITE (-4550 6100);
DISPLAY INVISIBLE (-4550 6100);
FORCEPROP 2 LAST $SEC 1
J 0
(-4550 6150);
DISPLAY 0.680851 (-4550 6150);
PAINT MONO (-4550 6150);
DISPLAY INVISIBLE (-4550 6150);
FORCEPROP 2 LAST CDS_SEC 1
J 0
(-4550 6150);
DISPLAY 1.021277 (-4550 6150);
DISPLAY INVISIBLE (-4550 6150);
FORCEADD OFFPAGE..4
R 2
(-6150 6250);
FORCEPROP 2 LAST $XR1 219 
J 0
(-6522 6250);
DISPLAY 0.638298 (-6522 6250);
PAINT MONO (-6522 6250);
FORCEPROP 2 LAST $XR0 214 
J 0
(-6402 6250);
DISPLAY 0.638298 (-6402 6250);
PAINT MONO (-6402 6250);
FORCEPROP 2 LAST CDS_LIB standard
J 0
(-6150 6250);
DISPLAY INVISIBLE (-6150 6250);
FORCEPROP 1 LAST OFFPAGE TRUE
J 2
(-6475 6125);
DISPLAY 0.872340 (-6475 6125);
PAINT GREEN (-6475 6125);
DISPLAY INVISIBLE (-6475 6125);
FORCEPROP 1 LAST COMMENT_BODY TRUE
J 2
(-6125 6150);
DISPLAY 0.872340 (-6125 6150);
PAINT GREEN (-6125 6150);
DISPLAY INVISIBLE (-6125 6150);
FORCEPROP 2 LAST PATH I12
J 0
(-6400 6300);
DISPLAY 1.021277 (-6400 6300);
DISPLAY INVISIBLE (-6400 6300);
FORCEADD GND..1
(-6350 6775);
FORCEPROP 3 LASTPIN (-6350 6825) SIG_NAME GND\g
J 0
(-6340 6835);
DISPLAY 0.659574 (-6340 6835);
PAINT MONO (-6340 6835);
DISPLAY INVISIBLE (-6340 6835);
FORCEPROP 1 LAST SIZE 1B
J 0
(-6275 6725);
DISPLAY 0.872340 (-6275 6725);
PAINT AQUA (-6275 6725);
DISPLAY INVISIBLE (-6275 6725);
FORCEPROP 2 LAST CDS_LIB logical_power
J 0
(-6350 6775);
DISPLAY INVISIBLE (-6350 6775);
FORCEPROP 1 LAST HDL_POWER GND
J 0
(-6350 6925);
DISPLAY 0.872340 (-6350 6925);
PAINT GREEN (-6350 6925);
DISPLAY INVISIBLE (-6350 6925);
FORCEPROP 1 LAST PATH I13
J 0
(-6275 6775);
DISPLAY 0.872340 (-6275 6775);
PAINT AQUA (-6275 6775);
DISPLAY INVISIBLE (-6275 6775);
FORCEADD Q_CAP..1
(-6350 7025);
FORCEPROP 1 LAST PART_NUMBER CH4106K1B01
J 0
(-6300 6875);
DISPLAY 0.638298 (-6300 6875);
DISPLAY INVISIBLE (-6300 6875);
FORCEPROP 1 LAST MATERIAL X7R
J 0
(-6300 6925);
DISPLAY 0.638298 (-6300 6925);
FORCEPROP 1 LAST PACK_TYPE C0402
J 0
(-6300 6825);
DISPLAY 0.638298 (-6300 6825);
FORCEPROP 1 LAST VALUE 100NF
J 0
(-6300 7075);
DISPLAY 0.638298 (-6300 7075);
FORCEPROP 1 LAST VOLTAGE 50V
J 0
(-6300 7025);
DISPLAY 0.638298 (-6300 7025);
FORCEPROP 1 LAST TOLERANCE 10%
J 0
(-6300 6975);
DISPLAY 0.638298 (-6300 6975);
FORCEPROP 1 LAST LOCATION PC1651
J 0
(-6300 7125);
DISPLAY 0.638298 (-6300 7125);
FORCEPROP 1 LASTPIN (-6350 7125) $PN 1
J 0
(-6340 7105);
DISPLAY 0.787234 (-6340 7105);
PAINT MONO (-6340 7105);
FORCEPROP 1 LASTPIN (-6350 6925) $PN 2
J 0
(-6340 6905);
DISPLAY 0.787234 (-6340 6905);
PAINT MONO (-6340 6905);
FORCEPROP 2 LAST CDS_LIB pure_quanta
J 0
(-6350 7025);
DISPLAY INVISIBLE (-6350 7025);
FORCEPROP 1 LAST PATH I14
J 0
(-6300 7175);
DISPLAY 0.978723 (-6300 7175);
PAINT WHITE (-6300 7175);
DISPLAY INVISIBLE (-6300 7175);
FORCEPROP 0 LAST $SEC 1
J 0
(-6300 7175);
DISPLAY 0.680851 (-6300 7175);
PAINT MONO (-6300 7175);
DISPLAY INVISIBLE (-6300 7175);
FORCEPROP 0 LAST CDS_SEC 1
J 0
(-6300 7175);
DISPLAY 1.021277 (-6300 7175);
DISPLAY INVISIBLE (-6300 7175);
FORCEADD VCCAUX15..1
(-6350 7425);
FORCEPROP 3 LASTPIN (-6350 7375) SIG_NAME P12V_AUX\g
J 0
(-6340 7385);
DISPLAY 0.659574 (-6340 7385);
PAINT MONO (-6340 7385);
DISPLAY INVISIBLE (-6340 7385);
FORCEPROP 1 LAST HDL_POWER P12V_AUX
J 1
(-6350 7467);
DISPLAY 0.617021 (-6350 7467);
PAINT GREEN (-6350 7467);
FORCEPROP 2 LAST BOM_COST VR_PCH
J 0
(-6350 7500);
DISPLAY 0.680851 (-6350 7500);
DISPLAY INVISIBLE (-6350 7500);
FORCEPROP 2 LAST CDS_LIB logical_power
J 0
(-6350 7425);
DISPLAY INVISIBLE (-6350 7425);
FORCEPROP 1 LAST PATH I15
J 0
(-6300 7450);
DISPLAY 0.872340 (-6300 7450);
PAINT AQUA (-6300 7450);
DISPLAY INVISIBLE (-6300 7450);
FORCEADD Q_INDUCTOR..1
(-5975 7250);
FORCEPROP 1 LAST PART_NUMBER CX220TN1001
J 0
(-6100 7360);
DISPLAY 0.617021 (-6100 7360);
PAINT BLUE (-6100 7360);
DISPLAY INVISIBLE (-6100 7360);
FORCEPROP 1 LAST MATERIAL IND
J 0
(-6100 7305);
DISPLAY 0.617021 (-6100 7305);
PAINT SKYBLUE (-6100 7305);
FORCEPROP 2 LAST PACK_TYPE SMLF
J 0
(-6050 7175);
DISPLAY 0.489362 (-6050 7175);
PAINT SKYBLUE (-6050 7175);
FORCEPROP 2 LAST VALUE BLM18SN220TN1D/8000MA
J 0
(-6050 7125);
DISPLAY 0.489362 (-6050 7125);
PAINT SKYBLUE (-6050 7125);
FORCEPROP 1 LAST LOCATION PL16
J 0
(-6225 7235);
DISPLAY 0.617021 (-6225 7235);
PAINT AQUA (-6225 7235);
FORCEPROP 2 LASTPIN (-6075 7225) $PN 1
J 2
(-6085 7235);
DISPLAY 0.617021 (-6085 7235);
FORCEPROP 2 LASTPIN (-5875 7225) $PN 2
J 0
(-5865 7235);
DISPLAY 0.617021 (-5865 7235);
FORCEPROP 2 LAST CDS_LIB pure_quanta
J 0
(-5975 7250);
PAINT MONO (-5975 7250);
DISPLAY INVISIBLE (-5975 7250);
FORCEPROP 1 LAST NEEDS_NO_SIZE TRUE
J 0
(-5975 7250);
DISPLAY 0.468085 (-5975 7250);
PAINT GREEN (-5975 7250);
DISPLAY INVISIBLE (-5975 7250);
FORCEPROP 1 LAST PATH I16
J 0
(-5900 7305);
DISPLAY 0.723404 (-5900 7305);
PAINT GREEN (-5900 7305);
DISPLAY INVISIBLE (-5900 7305);
FORCEPROP 2 LAST $SEC 1
J 0
(-6100 7400);
DISPLAY 0.680851 (-6100 7400);
PAINT MONO (-6100 7400);
DISPLAY INVISIBLE (-6100 7400);
FORCEPROP 2 LAST CDS_SEC 1
J 0
(-6100 7400);
DISPLAY 1.021277 (-6100 7400);
DISPLAY INVISIBLE (-6100 7400);
FORCEADD Q_RES..1
(-5000 6250);
FORCEPROP 1 LAST PART_NUMBER CS00002JB13
J 0
(-5050 6300);
DISPLAY 0.404255 (-5050 6300);
PAINT BLUE (-5050 6300);
DISPLAY INVISIBLE (-5050 6300);
FORCEPROP 1 LAST MATERIAL CHIP
J 0
(-4750 6250);
DISPLAY 0.617021 (-4750 6250);
PAINT SKYBLUE (-4750 6250);
FORCEPROP 1 LAST TOLERANCE 5%
J 0
(-4825 6250);
DISPLAY 0.617021 (-4825 6250);
PAINT SKYBLUE (-4825 6250);
FORCEPROP 1 LAST VALUE 0
J 2
(-4850 6250);
DISPLAY 0.617021 (-4850 6250);
PAINT SKYBLUE (-4850 6250);
FORCEPROP 1 LAST LOCATION R2358
J 0
(-5250 6250);
DISPLAY 0.617021 (-5250 6250);
PAINT AQUA (-5250 6250);
FORCEPROP 1 LASTPIN (-5100 6250) $PN 1
J 0
(-5088 6262);
DISPLAY 0.617021 (-5088 6262);
FORCEPROP 1 LASTPIN (-4900 6250) $PN 2
J 0
(-4938 6262);
DISPLAY 0.617021 (-4938 6262);
FORCEPROP 2 LAST CDS_LIB pure_quanta
J 0
(-5000 6250);
PAINT MONO (-5000 6250);
DISPLAY INVISIBLE (-5000 6250);
FORCEPROP 1 LAST WATTAGE 1/16W
J 2
(-4825 6325);
DISPLAY 0.404255 (-4825 6325);
PAINT SKYBLUE (-4825 6325);
DISPLAY INVISIBLE (-4825 6325);
FORCEPROP 1 LAST PACK_TYPE 0402LF
J 0
(-5050 6350);
DISPLAY 0.404255 (-5050 6350);
PAINT SKYBLUE (-5050 6350);
DISPLAY INVISIBLE (-5050 6350);
FORCEPROP 1 LAST PATH I17
J 0
(-5050 6400);
DISPLAY 0.978723 (-5050 6400);
PAINT WHITE (-5050 6400);
DISPLAY INVISIBLE (-5050 6400);
FORCEPROP 2 LAST $SEC 1
J 0
(-5050 6450);
DISPLAY 0.680851 (-5050 6450);
PAINT MONO (-5050 6450);
DISPLAY INVISIBLE (-5050 6450);
FORCEPROP 2 LAST CDS_SEC 1
J 0
(-5050 6450);
DISPLAY 1.021277 (-5050 6450);
DISPLAY INVISIBLE (-5050 6450);
FORCEADD UNIVERSAL_GND..1
(-5475 6700);
FORCEPROP 3 LASTPIN (-5475 6750) SIG_NAME GND\g
J 0
(-5465 6760);
DISPLAY 0.659574 (-5465 6760);
PAINT MONO (-5465 6760);
DISPLAY INVISIBLE (-5465 6760);
FORCEPROP 2 LAST CDS_LIB logical_power
J 0
(-5475 6700);
PAINT MONO (-5475 6700);
DISPLAY INVISIBLE (-5475 6700);
FORCEPROP 1 LAST HDL_POWER GND
J 1
(-5450 6625);
DISPLAY 0.872340 (-5450 6625);
PAINT GREEN (-5450 6625);
DISPLAY INVISIBLE (-5450 6625);
FORCEPROP 1 LAST PATH I18
J 0
(-5400 6700);
DISPLAY 0.872340 (-5400 6700);
PAINT AQUA (-5400 6700);
DISPLAY INVISIBLE (-5400 6700);
FORCEADD Q_CAP..1
(-5475 7050);
FORCEPROP 1 LAST PART_NUMBER CH6103KEA01
J 0
(-5425 6900);
DISPLAY 0.617021 (-5425 6900);
PAINT BLUE (-5425 6900);
DISPLAY INVISIBLE (-5425 6900);
FORCEPROP 1 LAST PACK_TYPE C0805
J 0
(-5425 6850);
DISPLAY 0.617021 (-5425 6850);
PAINT SKYBLUE (-5425 6850);
FORCEPROP 1 LAST VALUE 10UF
J 0
(-5425 7100);
DISPLAY 0.617021 (-5425 7100);
PAINT SKYBLUE (-5425 7100);
FORCEPROP 1 LAST TOLERANCE 10%
J 0
(-5425 7000);
DISPLAY 0.617021 (-5425 7000);
PAINT SKYBLUE (-5425 7000);
FORCEPROP 1 LAST MATERIAL X6S
J 0
(-5425 6950);
DISPLAY 0.617021 (-5425 6950);
PAINT SKYBLUE (-5425 6950);
FORCEPROP 1 LAST VOLTAGE 16V
J 0
(-5425 7050);
DISPLAY 0.617021 (-5425 7050);
PAINT SKYBLUE (-5425 7050);
FORCEPROP 1 LAST LOCATION PC1232
J 0
(-5425 7150);
DISPLAY 0.617021 (-5425 7150);
PAINT AQUA (-5425 7150);
FORCEPROP 1 LASTPIN (-5475 7150) $PN 1
J 0
(-5465 7130);
DISPLAY 0.617021 (-5465 7130);
PAINT MONO (-5465 7130);
FORCEPROP 1 LASTPIN (-5475 6950) $PN 2
J 0
(-5465 6930);
DISPLAY 0.617021 (-5465 6930);
PAINT MONO (-5465 6930);
FORCEPROP 2 LAST CDS_LIB pure_quanta
J 0
(-5475 7050);
DISPLAY INVISIBLE (-5475 7050);
FORCEPROP 1 LAST PATH I19
J 0
(-5425 7200);
DISPLAY 0.978723 (-5425 7200);
PAINT WHITE (-5425 7200);
DISPLAY INVISIBLE (-5425 7200);
FORCEPROP 0 LAST $SEC 1
J 0
(-5425 7200);
DISPLAY 0.680851 (-5425 7200);
PAINT MONO (-5425 7200);
DISPLAY INVISIBLE (-5425 7200);
FORCEPROP 0 LAST CDS_SEC 1
J 0
(-5425 7200);
DISPLAY 1.021277 (-5425 7200);
DISPLAY INVISIBLE (-5425 7200);
FORCEADD Q_RES..1
(-4750 3950);
FORCEPROP 1 LAST PART_NUMBER CS00002JB13
J 0
(-4800 4050);
DISPLAY 0.617021 (-4800 4050);
PAINT BLUE (-4800 4050);
DISPLAY INVISIBLE (-4800 4050);
FORCEPROP 1 LAST MATERIAL EMPTY
J 0
(-4750 3800);
DISPLAY 0.617021 (-4750 3800);
PAINT RED (-4750 3800);
FORCEPROP 1 LAST PACK_TYPE 0402LF
J 0
(-4500 3800);
DISPLAY 0.617021 (-4500 3800);
PAINT SKYBLUE (-4500 3800);
FORCEPROP 1 LAST TOLERANCE 5%
J 0
(-4750 3850);
DISPLAY 0.617021 (-4750 3850);
PAINT SKYBLUE (-4750 3850);
FORCEPROP 1 LAST VALUE 0
J 2
(-4775 3850);
DISPLAY 0.617021 (-4775 3850);
PAINT SKYBLUE (-4775 3850);
FORCEPROP 1 LAST WATTAGE 1/16W
J 2
(-4775 3800);
DISPLAY 0.617021 (-4775 3800);
PAINT SKYBLUE (-4775 3800);
FORCEPROP 1 LAST LOCATION PR396
J 0
(-4800 4000);
DISPLAY 0.617021 (-4800 4000);
PAINT AQUA (-4800 4000);
FORCEPROP 2 LAST CDS_LIB pure_quanta
J 0
(-4750 3950);
DISPLAY INVISIBLE (-4750 3950);
FORCEPROP 1 LAST PATH I2
J 0
(-4800 4100);
DISPLAY 0.978723 (-4800 4100);
PAINT WHITE (-4800 4100);
DISPLAY INVISIBLE (-4800 4100);
FORCEPROP 0 LAST $SEC 1
J 0
(-4800 4100);
DISPLAY INVISIBLE (-4800 4100);
FORCEPROP 0 LAST CDS_SEC 1
J 0
(-4800 4100);
DISPLAY INVISIBLE (-4800 4100);
FORCEPROP 1 LASTPIN (-4850 3950) $PN 1
J 0
(-4838 3962);
DISPLAY 0.787234 (-4838 3962);
PAINT MONO (-4838 3962);
DISPLAY INVISIBLE (-4838 3962);
FORCEPROP 1 LASTPIN (-4650 3950) $PN 2
J 0
(-4688 3962);
DISPLAY 0.787234 (-4688 3962);
PAINT MONO (-4688 3962);
DISPLAY INVISIBLE (-4688 3962);
FORCEADD Q_CAP..1
(-5025 7050);
FORCEPROP 1 LAST PART_NUMBER CH6103KEA01
J 0
(-4975 6900);
DISPLAY 0.617021 (-4975 6900);
PAINT BLUE (-4975 6900);
DISPLAY INVISIBLE (-4975 6900);
FORCEPROP 1 LAST MATERIAL X6S
J 0
(-4975 6950);
DISPLAY 0.617021 (-4975 6950);
PAINT SKYBLUE (-4975 6950);
FORCEPROP 1 LAST PACK_TYPE C0805
J 0
(-4975 6850);
DISPLAY 0.617021 (-4975 6850);
PAINT SKYBLUE (-4975 6850);
FORCEPROP 1 LAST VOLTAGE 16V
J 0
(-4975 7050);
DISPLAY 0.617021 (-4975 7050);
PAINT SKYBLUE (-4975 7050);
FORCEPROP 1 LAST TOLERANCE 10%
J 0
(-4975 7000);
DISPLAY 0.617021 (-4975 7000);
PAINT SKYBLUE (-4975 7000);
FORCEPROP 1 LAST VALUE 10UF
J 0
(-4975 7100);
DISPLAY 0.617021 (-4975 7100);
PAINT SKYBLUE (-4975 7100);
FORCEPROP 1 LAST LOCATION PC1233
J 0
(-4975 7150);
DISPLAY 0.617021 (-4975 7150);
PAINT AQUA (-4975 7150);
FORCEPROP 1 LASTPIN (-5025 7150) $PN 1
J 0
(-5015 7130);
DISPLAY 0.617021 (-5015 7130);
PAINT MONO (-5015 7130);
FORCEPROP 1 LASTPIN (-5025 6950) $PN 2
J 0
(-5015 6930);
DISPLAY 0.617021 (-5015 6930);
PAINT MONO (-5015 6930);
FORCEPROP 2 LAST CDS_LIB pure_quanta
J 0
(-5025 7050);
DISPLAY INVISIBLE (-5025 7050);
FORCEPROP 1 LAST PATH I20
J 0
(-4975 7200);
DISPLAY 0.978723 (-4975 7200);
PAINT WHITE (-4975 7200);
DISPLAY INVISIBLE (-4975 7200);
FORCEPROP 0 LAST $SEC 1
J 0
(-4975 7200);
DISPLAY 0.680851 (-4975 7200);
PAINT MONO (-4975 7200);
DISPLAY INVISIBLE (-4975 7200);
FORCEPROP 0 LAST CDS_SEC 1
J 0
(-4975 7200);
DISPLAY 1.021277 (-4975 7200);
DISPLAY INVISIBLE (-4975 7200);
FORCEADD Q_CAP..1
(-4600 7050);
FORCEPROP 1 LAST PART_NUMBER CH4106K1B01
J 0
(-4550 6900);
DISPLAY 0.617021 (-4550 6900);
PAINT BLUE (-4550 6900);
DISPLAY INVISIBLE (-4550 6900);
FORCEPROP 1 LAST MATERIAL X7R
J 0
(-4550 6950);
DISPLAY 0.617021 (-4550 6950);
PAINT SKYBLUE (-4550 6950);
FORCEPROP 1 LAST PACK_TYPE C0402
J 0
(-4550 6850);
DISPLAY 0.617021 (-4550 6850);
PAINT SKYBLUE (-4550 6850);
FORCEPROP 1 LAST VOLTAGE 50V
J 0
(-4550 7050);
DISPLAY 0.617021 (-4550 7050);
PAINT SKYBLUE (-4550 7050);
FORCEPROP 1 LAST VALUE 100NF
J 0
(-4550 7100);
DISPLAY 0.617021 (-4550 7100);
PAINT SKYBLUE (-4550 7100);
FORCEPROP 1 LAST TOLERANCE 10%
J 0
(-4550 7000);
DISPLAY 0.617021 (-4550 7000);
PAINT SKYBLUE (-4550 7000);
FORCEPROP 1 LAST LOCATION PC1234
J 0
(-4550 7150);
DISPLAY 0.617021 (-4550 7150);
PAINT AQUA (-4550 7150);
FORCEPROP 1 LASTPIN (-4600 7150) $PN 1
J 0
(-4590 7130);
DISPLAY 0.617021 (-4590 7130);
FORCEPROP 1 LASTPIN (-4600 6950) $PN 2
J 0
(-4590 6930);
DISPLAY 0.617021 (-4590 6930);
FORCEPROP 2 LAST CDS_LIB pure_quanta
J 0
(-4600 7050);
PAINT MONO (-4600 7050);
DISPLAY INVISIBLE (-4600 7050);
FORCEPROP 1 LAST PATH I21
J 0
(-4550 7200);
DISPLAY 0.978723 (-4550 7200);
PAINT WHITE (-4550 7200);
DISPLAY INVISIBLE (-4550 7200);
FORCEPROP 1 LAST LOCATION PC1234
J 0
(-4550 7225);
DISPLAY 1.021277 (-4550 7225);
PAINT AQUA (-4550 7225);
DISPLAY INVISIBLE (-4550 7225);
FORCEPROP 2 LAST $SEC 1
J 0
(-4550 7250);
DISPLAY 0.680851 (-4550 7250);
PAINT MONO (-4550 7250);
DISPLAY INVISIBLE (-4550 7250);
FORCEPROP 2 LAST CDS_SEC 1
J 0
(-4550 7250);
DISPLAY 1.021277 (-4550 7250);
DISPLAY INVISIBLE (-4550 7250);
FORCEADD UNIVERSAL_POWER..1
(-4150 4100);
FORCEPROP 3 LASTPIN (-4150 4050) SIG_NAME PVCC1_AUX\g
J 0
(-4140 4060);
DISPLAY 0.659574 (-4140 4060);
PAINT MONO (-4140 4060);
DISPLAY INVISIBLE (-4140 4060);
FORCEPROP 1 LAST HDL_POWER PVCC1_AUX
J 1
(-4150 4150);
DISPLAY 0.617021 (-4150 4150);
PAINT GREEN (-4150 4150);
FORCEPROP 2 LAST CDS_LIB logical_power
J 0
(-4150 4100);
DISPLAY INVISIBLE (-4150 4100);
FORCEPROP 1 LAST PATH I22
J 0
(-4100 4125);
DISPLAY 0.872340 (-4100 4125);
PAINT AQUA (-4100 4125);
DISPLAY INVISIBLE (-4100 4125);
FORCEADD UNIVERSAL_POWER..1
(-4150 4500);
FORCEPROP 3 LASTPIN (-4150 4450) SIG_NAME PVCC1_AUX\g
J 0
(-4140 4460);
DISPLAY 0.659574 (-4140 4460);
PAINT MONO (-4140 4460);
DISPLAY INVISIBLE (-4140 4460);
FORCEPROP 1 LAST HDL_POWER PVCC1_AUX
J 1
(-4150 4550);
DISPLAY 0.617021 (-4150 4550);
PAINT GREEN (-4150 4550);
FORCEPROP 2 LAST CDS_LIB logical_power
J 0
(-4150 4500);
DISPLAY INVISIBLE (-4150 4500);
FORCEPROP 1 LAST PATH I23
J 0
(-4100 4525);
DISPLAY 0.872340 (-4100 4525);
PAINT AQUA (-4100 4525);
DISPLAY INVISIBLE (-4100 4525);
FORCEADD Q_RES..2
(-4325 5150);
FORCEPROP 1 LAST PART_NUMBER CS41502FB04
J 0
(-4285 5025);
DISPLAY 0.617021 (-4285 5025);
PAINT BLUE (-4285 5025);
DISPLAY INVISIBLE (-4285 5025);
FORCEPROP 1 LAST MATERIAL CHIP
J 0
(-4285 5075);
DISPLAY 0.617021 (-4285 5075);
PAINT SKYBLUE (-4285 5075);
FORCEPROP 1 LAST VALUE 150K
J 0
(-4280 5225);
DISPLAY 0.617021 (-4280 5225);
PAINT SKYBLUE (-4280 5225);
FORCEPROP 1 LAST WATTAGE 1/16W
J 0
(-4285 5125);
DISPLAY 0.617021 (-4285 5125);
PAINT SKYBLUE (-4285 5125);
FORCEPROP 1 LAST TOLERANCE 1%
J 0
(-4280 5175);
DISPLAY 0.617021 (-4280 5175);
PAINT SKYBLUE (-4280 5175);
FORCEPROP 1 LAST PACK_TYPE 0402LF
J 0
(-4285 4975);
DISPLAY 0.617021 (-4285 4975);
PAINT SKYBLUE (-4285 4975);
FORCEPROP 1 LAST LOCATION PR1330
J 0
(-4280 5275);
DISPLAY 0.617021 (-4280 5275);
PAINT AQUA (-4280 5275);
FORCEPROP 1 LASTPIN (-4325 5250) $PN 1
J 0
(-4320 5212);
DISPLAY 0.617021 (-4320 5212);
PAINT MONO (-4320 5212);
FORCEPROP 1 LASTPIN (-4325 5050) $PN 2
J 0
(-4320 5060);
DISPLAY 0.617021 (-4320 5060);
PAINT MONO (-4320 5060);
FORCEPROP 2 LAST CDS_LIB pure_quanta
J 0
(-4325 5150);
DISPLAY INVISIBLE (-4325 5150);
FORCEPROP 1 LAST PATH I24
J 0
(-4275 5325);
DISPLAY 0.978723 (-4275 5325);
PAINT WHITE (-4275 5325);
DISPLAY INVISIBLE (-4275 5325);
FORCEPROP 2 LAST $SEC 1
J 0
(-4275 5375);
DISPLAY 0.680851 (-4275 5375);
PAINT MONO (-4275 5375);
DISPLAY INVISIBLE (-4275 5375);
FORCEPROP 2 LAST CDS_SEC 1
J 0
(-4275 5375);
DISPLAY 1.021277 (-4275 5375);
DISPLAY INVISIBLE (-4275 5375);
FORCEADD UNIVERSAL_GND..1
(-4325 4900);
FORCEPROP 3 LASTPIN (-4325 4950) SIG_NAME GND\g
J 0
(-4315 4960);
DISPLAY 0.659574 (-4315 4960);
PAINT MONO (-4315 4960);
DISPLAY INVISIBLE (-4315 4960);
FORCEPROP 2 LAST CDS_LIB logical_power
J 0
(-4325 4900);
DISPLAY INVISIBLE (-4325 4900);
FORCEPROP 1 LAST HDL_POWER GND
J 1
(-4300 4825);
DISPLAY 0.872340 (-4300 4825);
PAINT GREEN (-4300 4825);
DISPLAY INVISIBLE (-4300 4825);
FORCEPROP 1 LAST PATH I25
J 0
(-4250 4900);
DISPLAY 0.872340 (-4250 4900);
PAINT AQUA (-4250 4900);
DISPLAY INVISIBLE (-4250 4900);
FORCEADD NB682GDZ..1
(-3150 6075);
FORCEPROP 1 LAST PART_NUMBER AL000682001
J 0
(-3395 6934);
DISPLAY 0.723404 (-3395 6934);
PAINT GREEN (-3395 6934);
DISPLAY INVISIBLE (-3395 6934);
FORCEPROP 2 LAST VALUE NB682GD-Z
J 0
(-3400 7075);
DISPLAY 0.617021 (-3400 7075);
PAINT SKYBLUE (-3400 7075);
FORCEPROP 2 LAST PART_TYPE SMLF
J 0
(-3400 7125);
DISPLAY 1.021277 (-3400 7125);
FORCEPROP 1 LAST MATERIAL IC
J 0
(-3395 6807);
DISPLAY 0.723404 (-3395 6807);
PAINT GREEN (-3395 6807);
FORCEPROP 1 LAST LOCATION PU74
J 0
(-3400 7000);
DISPLAY 0.723404 (-3400 7000);
PAINT GREEN (-3400 7000);
FORCEPROP 2 LASTPIN (-3550 6050) $PN 10
J 2
(-3560 6060);
DISPLAY 0.680851 (-3560 6060);
PAINT MONO (-3560 6060);
FORCEPROP 2 LASTPIN (-2750 5400) $PN 11
J 0
(-2740 5410);
DISPLAY 0.680851 (-2740 5410);
PAINT MONO (-2740 5410);
FORCEPROP 2 LASTPIN (-2750 6550) $PN 9
J 0
(-2740 6560);
DISPLAY 0.680851 (-2740 6560);
PAINT MONO (-2740 6560);
FORCEPROP 2 LASTPIN (-3550 5550) $PN 4
J 2
(-3560 5560);
DISPLAY 0.680851 (-3560 5560);
PAINT MONO (-3560 5560);
FORCEPROP 2 LASTPIN (-3550 5650) $PN 3
J 2
(-3560 5660);
DISPLAY 0.680851 (-3560 5660);
PAINT MONO (-3560 5660);
FORCEPROP 2 LASTPIN (-3550 6250) $PN 5
J 2
(-3560 6260);
DISPLAY 0.680851 (-3560 6260);
PAINT MONO (-3560 6260);
FORCEPROP 2 LASTPIN (-3550 5750) $PN 6
J 2
(-3560 5760);
DISPLAY 0.680851 (-3560 5760);
PAINT MONO (-3560 5760);
FORCEPROP 2 LASTPIN (-3550 5400) $PN 7
J 2
(-3560 5410);
DISPLAY 0.680851 (-3560 5410);
PAINT MONO (-3560 5410);
FORCEPROP 2 LASTPIN (-2750 6750) $PN 13
J 0
(-2740 6760);
DISPLAY 0.680851 (-2740 6760);
PAINT MONO (-2740 6760);
FORCEPROP 2 LASTPIN (-2750 5450) $PN 2
J 0
(-2740 5460);
DISPLAY 0.680851 (-2740 5460);
PAINT MONO (-2740 5460);
FORCEPROP 2 LASTPIN (-2750 6250) $PN 8
J 0
(-2740 6260);
DISPLAY 0.680851 (-2740 6260);
PAINT MONO (-2740 6260);
FORCEPROP 2 LASTPIN (-3550 6750) $PN 1
J 2
(-3560 6760);
DISPLAY 0.680851 (-3560 6760);
PAINT MONO (-3560 6760);
FORCEPROP 2 LASTPIN (-2750 5550) $PN 12
J 0
(-2740 5560);
DISPLAY 0.680851 (-2740 5560);
PAINT MONO (-2740 5560);
FORCEPROP 2 LAST SEC_TYPE 
J 0
(-3400 7175);
DISPLAY 1.021277 (-3400 7175);
DISPLAY INVISIBLE (-3400 7175);
FORCEPROP 2 LAST CDS_LIB pure_quanta
J 0
(-3150 6075);
DISPLAY INVISIBLE (-3150 6075);
FORCEPROP 1 LAST NEEDS_NO_SIZE TRUE
J 0
(-3150 6075);
DISPLAY 0.723404 (-3150 6075);
PAINT GREEN (-3150 6075);
DISPLAY INVISIBLE (-3150 6075);
FORCEPROP 1 LAST CDS_LMAN_SYM_OUTLINE -250,725,250,-725
J 0
(-3150 6075);
DISPLAY 0.468085 (-3150 6075);
PAINT GREEN (-3150 6075);
DISPLAY INVISIBLE (-3150 6075);
FORCEPROP 1 LAST PATH I26
J 0
(-3150 6075);
DISPLAY 0.723404 (-3150 6075);
PAINT GREEN (-3150 6075);
DISPLAY INVISIBLE (-3150 6075);
FORCEPROP 2 LAST SEC 1
J 0
(-3400 7175);
DISPLAY 0.680851 (-3400 7175);
PAINT MONO (-3400 7175);
DISPLAY INVISIBLE (-3400 7175);
FORCEADD UNIVERSAL_GND..1
(-2650 4950);
FORCEPROP 3 LASTPIN (-2650 5000) SIG_NAME GND\g
J 0
(-2640 5010);
DISPLAY 0.659574 (-2640 5010);
PAINT MONO (-2640 5010);
DISPLAY INVISIBLE (-2640 5010);
FORCEPROP 2 LAST CDS_LIB logical_power
J 0
(-2650 4950);
DISPLAY INVISIBLE (-2650 4950);
FORCEPROP 1 LAST HDL_POWER GND
J 1
(-2625 4875);
DISPLAY 0.872340 (-2625 4875);
PAINT GREEN (-2625 4875);
DISPLAY INVISIBLE (-2625 4875);
FORCEPROP 1 LAST PATH I27
J 0
(-2575 4950);
DISPLAY 0.872340 (-2575 4950);
PAINT AQUA (-2575 4950);
DISPLAY INVISIBLE (-2575 4950);
FORCEADD Q_CAP..1
(-925 6050);
FORCEPROP 1 LAST PART_NUMBER CH4106K1B01
J 0
(-875 5900);
DISPLAY 0.617021 (-875 5900);
PAINT BLUE (-875 5900);
DISPLAY INVISIBLE (-875 5900);
FORCEPROP 1 LAST TOLERANCE 10%
J 0
(-875 6000);
DISPLAY 0.617021 (-875 6000);
PAINT SKYBLUE (-875 6000);
FORCEPROP 1 LAST VOLTAGE 50V
J 0
(-875 6050);
DISPLAY 0.617021 (-875 6050);
PAINT SKYBLUE (-875 6050);
FORCEPROP 1 LAST MATERIAL X7R
J 0
(-875 5950);
DISPLAY 0.617021 (-875 5950);
PAINT SKYBLUE (-875 5950);
FORCEPROP 1 LAST PACK_TYPE C0402
J 0
(-875 5850);
DISPLAY 0.617021 (-875 5850);
PAINT SKYBLUE (-875 5850);
FORCEPROP 1 LAST VALUE 100NF
J 0
(-875 6100);
DISPLAY 0.617021 (-875 6100);
PAINT SKYBLUE (-875 6100);
FORCEPROP 1 LAST LOCATION PC1236
J 0
(-875 6150);
DISPLAY 0.617021 (-875 6150);
PAINT AQUA (-875 6150);
FORCEPROP 1 LASTPIN (-925 6150) $PN 1
J 0
(-915 6130);
DISPLAY 0.617021 (-915 6130);
FORCEPROP 1 LASTPIN (-925 5950) $PN 2
J 0
(-915 5930);
DISPLAY 0.617021 (-915 5930);
FORCEPROP 2 LAST CDS_LIB pure_quanta
J 0
(-925 6050);
PAINT MONO (-925 6050);
DISPLAY INVISIBLE (-925 6050);
FORCEPROP 1 LAST PATH I28
J 0
(-875 6200);
DISPLAY 0.978723 (-875 6200);
PAINT WHITE (-875 6200);
DISPLAY INVISIBLE (-875 6200);
FORCEPROP 2 LAST $SEC 1
J 0
(-875 6250);
DISPLAY 0.680851 (-875 6250);
PAINT MONO (-875 6250);
DISPLAY INVISIBLE (-875 6250);
FORCEPROP 2 LAST CDS_SEC 1
J 0
(-875 6250);
DISPLAY 1.021277 (-875 6250);
DISPLAY INVISIBLE (-875 6250);
FORCEADD Q_CAP..1
(-525 6050);
FORCEPROP 1 LAST PART_NUMBER CH622KMEA03
J 0
(-475 5900);
DISPLAY 0.617021 (-475 5900);
PAINT BLUE (-475 5900);
DISPLAY INVISIBLE (-475 5900);
FORCEPROP 1 LAST VALUE 22UF
J 0
(-475 6100);
DISPLAY 0.617021 (-475 6100);
PAINT SKYBLUE (-475 6100);
FORCEPROP 1 LAST MATERIAL X6S
J 0
(-475 5950);
DISPLAY 0.617021 (-475 5950);
PAINT SKYBLUE (-475 5950);
FORCEPROP 1 LAST TOLERANCE 20%
J 0
(-475 6000);
DISPLAY 0.617021 (-475 6000);
PAINT SKYBLUE (-475 6000);
FORCEPROP 1 LAST PACK_TYPE C0805
J 0
(-475 5850);
DISPLAY 0.617021 (-475 5850);
PAINT SKYBLUE (-475 5850);
FORCEPROP 1 LAST VOLTAGE 4V
J 0
(-475 6050);
DISPLAY 0.617021 (-475 6050);
PAINT SKYBLUE (-475 6050);
FORCEPROP 1 LAST LOCATION PC1237
J 0
(-475 6150);
DISPLAY 0.617021 (-475 6150);
PAINT AQUA (-475 6150);
FORCEPROP 1 LASTPIN (-525 6150) $PN 1
J 0
(-515 6130);
DISPLAY 0.617021 (-515 6130);
FORCEPROP 1 LASTPIN (-525 5950) $PN 2
J 0
(-515 5930);
DISPLAY 0.617021 (-515 5930);
FORCEPROP 2 LAST BOM_COST VR_PCH
J 0
(-475 6200);
DISPLAY 0.680851 (-475 6200);
DISPLAY INVISIBLE (-475 6200);
FORCEPROP 2 LAST CDS_LIB pure_quanta
J 0
(-525 6050);
PAINT MONO (-525 6050);
DISPLAY INVISIBLE (-525 6050);
FORCEPROP 1 LAST PATH I29
J 0
(-475 6200);
DISPLAY 0.978723 (-475 6200);
PAINT WHITE (-475 6200);
DISPLAY INVISIBLE (-475 6200);
FORCEPROP 2 LAST $SEC 1
J 0
(-475 6250);
DISPLAY 0.680851 (-475 6250);
PAINT MONO (-475 6250);
DISPLAY INVISIBLE (-475 6250);
FORCEPROP 2 LAST CDS_SEC 1
J 0
(-475 6250);
DISPLAY 1.021277 (-475 6250);
DISPLAY INVISIBLE (-475 6250);
FORCEADD UNIVERSAL_GND..1
(-5750 4900);
FORCEPROP 3 LASTPIN (-5750 4950) SIG_NAME GND\g
J 0
(-5740 4960);
DISPLAY 0.659574 (-5740 4960);
PAINT MONO (-5740 4960);
DISPLAY INVISIBLE (-5740 4960);
FORCEPROP 2 LAST CDS_LIB logical_power
J 0
(-5750 4900);
DISPLAY INVISIBLE (-5750 4900);
FORCEPROP 1 LAST HDL_POWER GND
J 1
(-5725 4825);
DISPLAY 0.872340 (-5725 4825);
PAINT GREEN (-5725 4825);
DISPLAY INVISIBLE (-5725 4825);
FORCEPROP 1 LAST PATH I3
J 0
(-5675 4900);
DISPLAY 0.872340 (-5675 4900);
PAINT AQUA (-5675 4900);
DISPLAY INVISIBLE (-5675 4900);
FORCEADD Q_CAP..1
(-1875 6475);
FORCEPROP 1 LAST PART_NUMBER CH4224K1B01
J 0
(-1825 6325);
DISPLAY 0.617021 (-1825 6325);
PAINT BLUE (-1825 6325);
DISPLAY INVISIBLE (-1825 6325);
FORCEPROP 1 LAST MATERIAL X7R
J 0
(-1825 6375);
DISPLAY 0.617021 (-1825 6375);
PAINT SKYBLUE (-1825 6375);
FORCEPROP 1 LAST TOLERANCE 10%
J 0
(-1825 6425);
DISPLAY 0.617021 (-1825 6425);
PAINT SKYBLUE (-1825 6425);
FORCEPROP 1 LAST VOLTAGE 25V
J 0
(-1825 6475);
DISPLAY 0.617021 (-1825 6475);
PAINT SKYBLUE (-1825 6475);
FORCEPROP 1 LAST PACK_TYPE C0402
J 0
(-1825 6275);
DISPLAY 0.617021 (-1825 6275);
PAINT SKYBLUE (-1825 6275);
FORCEPROP 1 LAST VALUE 0.22UF
J 0
(-1825 6525);
DISPLAY 0.617021 (-1825 6525);
PAINT SKYBLUE (-1825 6525);
FORCEPROP 1 LAST LOCATION PC1235
J 0
(-1825 6575);
DISPLAY 0.617021 (-1825 6575);
PAINT AQUA (-1825 6575);
FORCEPROP 1 LASTPIN (-1875 6575) $PN 1
J 0
(-1865 6555);
DISPLAY 0.617021 (-1865 6555);
PAINT MONO (-1865 6555);
FORCEPROP 1 LASTPIN (-1875 6375) $PN 2
J 0
(-1865 6355);
DISPLAY 0.617021 (-1865 6355);
PAINT MONO (-1865 6355);
FORCEPROP 2 LAST CDS_LIB pure_quanta
J 0
(-1875 6475);
DISPLAY INVISIBLE (-1875 6475);
FORCEPROP 1 LAST PATH I30
J 0
(-1825 6625);
DISPLAY 0.978723 (-1825 6625);
PAINT WHITE (-1825 6625);
DISPLAY INVISIBLE (-1825 6625);
FORCEPROP 2 LAST $SEC 1
J 0
(-1825 6675);
DISPLAY 0.680851 (-1825 6675);
PAINT MONO (-1825 6675);
DISPLAY INVISIBLE (-1825 6675);
FORCEPROP 2 LAST CDS_SEC 1
J 0
(-1825 6675);
DISPLAY 1.021277 (-1825 6675);
DISPLAY INVISIBLE (-1825 6675);
FORCEADD Q_RES..2
(-1875 7125);
FORCEPROP 1 LAST PART_NUMBER CS31002FB08
J 0
(-1835 7000);
DISPLAY 0.617021 (-1835 7000);
PAINT BLUE (-1835 7000);
DISPLAY INVISIBLE (-1835 7000);
FORCEPROP 1 LAST VALUE 10K
J 0
(-1830 7200);
DISPLAY 0.617021 (-1830 7200);
PAINT SKYBLUE (-1830 7200);
FORCEPROP 1 LAST TOLERANCE 1%
J 0
(-1830 7150);
DISPLAY 0.617021 (-1830 7150);
PAINT SKYBLUE (-1830 7150);
FORCEPROP 1 LAST WATTAGE 1/16W
J 0
(-1835 7100);
DISPLAY 0.617021 (-1835 7100);
PAINT SKYBLUE (-1835 7100);
FORCEPROP 1 LAST PACK_TYPE 0402LF
J 0
(-1835 6950);
DISPLAY 0.617021 (-1835 6950);
PAINT SKYBLUE (-1835 6950);
FORCEPROP 1 LAST MATERIAL CHIP
J 0
(-1835 7050);
DISPLAY 0.617021 (-1835 7050);
PAINT SKYBLUE (-1835 7050);
FORCEPROP 1 LAST LOCATION R2359
J 0
(-1830 7250);
DISPLAY 0.617021 (-1830 7250);
PAINT AQUA (-1830 7250);
FORCEPROP 1 LASTPIN (-1875 7225) $PN 1
J 0
(-1870 7187);
DISPLAY 0.617021 (-1870 7187);
FORCEPROP 1 LASTPIN (-1875 7025) $PN 2
J 0
(-1870 7035);
DISPLAY 0.617021 (-1870 7035);
FORCEPROP 2 LAST BOM_COST VR_PCH
J 0
(-1825 7300);
DISPLAY 0.680851 (-1825 7300);
DISPLAY INVISIBLE (-1825 7300);
FORCEPROP 2 LAST CDS_LIB pure_quanta
J 0
(-1875 7125);
DISPLAY INVISIBLE (-1875 7125);
FORCEPROP 1 LAST PATH I31
J 0
(-1825 7300);
DISPLAY 0.978723 (-1825 7300);
PAINT WHITE (-1825 7300);
DISPLAY INVISIBLE (-1825 7300);
FORCEPROP 0 LAST $SEC 1
J 0
(-1825 7350);
DISPLAY 0.680851 (-1825 7350);
PAINT MONO (-1825 7350);
DISPLAY INVISIBLE (-1825 7350);
FORCEPROP 0 LAST CDS_SEC 1
J 0
(-1825 7350);
DISPLAY 0.680851 (-1825 7350);
DISPLAY INVISIBLE (-1825 7350);
FORCEADD UNIVERSAL_POWER..1
(-1875 7375);
FORCEPROP 3 LASTPIN (-1875 7325) SIG_NAME P3V3_AUX\g
J 0
(-1865 7335);
DISPLAY 0.659574 (-1865 7335);
PAINT MONO (-1865 7335);
DISPLAY INVISIBLE (-1865 7335);
FORCEPROP 1 LAST HDL_POWER P3V3_AUX
J 1
(-1875 7425);
DISPLAY 0.617021 (-1875 7425);
PAINT GREEN (-1875 7425);
FORCEPROP 2 LAST CDS_LIB logical_power
J 0
(-1875 7375);
DISPLAY INVISIBLE (-1875 7375);
FORCEPROP 1 LAST PATH I32
J 0
(-1825 7400);
DISPLAY 0.872340 (-1825 7400);
PAINT AQUA (-1825 7400);
DISPLAY INVISIBLE (-1825 7400);
FORCEADD Q_RES..1
(-1325 6750);
FORCEPROP 1 LAST PART_NUMBER CS00002JB13
J 0
(-1400 6800);
DISPLAY 0.617021 (-1400 6800);
PAINT BLUE (-1400 6800);
DISPLAY INVISIBLE (-1400 6800);
FORCEPROP 1 LAST MATERIAL CHIP
J 0
(-1075 6750);
DISPLAY 0.617021 (-1075 6750);
PAINT SKYBLUE (-1075 6750);
FORCEPROP 1 LAST TOLERANCE 5%
J 0
(-1150 6750);
DISPLAY 0.617021 (-1150 6750);
PAINT SKYBLUE (-1150 6750);
FORCEPROP 1 LAST VALUE 0
J 2
(-1175 6750);
DISPLAY 0.617021 (-1175 6750);
PAINT SKYBLUE (-1175 6750);
FORCEPROP 1 LAST LOCATION R2360
J 0
(-1575 6750);
DISPLAY 0.617021 (-1575 6750);
PAINT AQUA (-1575 6750);
FORCEPROP 1 LASTPIN (-1425 6750) $PN 1
J 0
(-1413 6762);
DISPLAY 0.617021 (-1413 6762);
FORCEPROP 1 LASTPIN (-1225 6750) $PN 2
J 0
(-1263 6762);
DISPLAY 0.617021 (-1263 6762);
FORCEPROP 2 LAST CDS_LIB pure_quanta
J 0
(-1325 6750);
PAINT MONO (-1325 6750);
DISPLAY INVISIBLE (-1325 6750);
FORCEPROP 1 LAST WATTAGE 1/16W
J 2
(-1150 6825);
DISPLAY 0.404255 (-1150 6825);
PAINT SKYBLUE (-1150 6825);
DISPLAY INVISIBLE (-1150 6825);
FORCEPROP 1 LAST PACK_TYPE 0402LF
J 0
(-1375 6850);
DISPLAY 0.404255 (-1375 6850);
PAINT SKYBLUE (-1375 6850);
DISPLAY INVISIBLE (-1375 6850);
FORCEPROP 1 LAST PATH I34
J 0
(-1375 6900);
DISPLAY 0.978723 (-1375 6900);
PAINT WHITE (-1375 6900);
DISPLAY INVISIBLE (-1375 6900);
FORCEPROP 2 LAST $SEC 1
J 0
(-1375 6950);
DISPLAY 0.680851 (-1375 6950);
PAINT MONO (-1375 6950);
DISPLAY INVISIBLE (-1375 6950);
FORCEPROP 2 LAST CDS_SEC 1
J 0
(-1375 6950);
DISPLAY 1.021277 (-1375 6950);
DISPLAY INVISIBLE (-1375 6950);
FORCEADD UNIVERSAL_GND..1
(-775 6325);
FORCEPROP 3 LASTPIN (-775 6375) SIG_NAME GND\g
J 0
(-765 6385);
DISPLAY 0.659574 (-765 6385);
PAINT MONO (-765 6385);
DISPLAY INVISIBLE (-765 6385);
FORCEPROP 2 LAST CDS_LIB logical_power
J 0
(-775 6325);
PAINT MONO (-775 6325);
DISPLAY INVISIBLE (-775 6325);
FORCEPROP 1 LAST HDL_POWER GND
J 1
(-750 6250);
DISPLAY 0.872340 (-750 6250);
PAINT GREEN (-750 6250);
DISPLAY INVISIBLE (-750 6250);
FORCEPROP 1 LAST PATH I35
J 0
(-700 6325);
DISPLAY 0.872340 (-700 6325);
PAINT AQUA (-700 6325);
DISPLAY INVISIBLE (-700 6325);
FORCEADD Q_CAP..1
(-775 6575);
FORCEPROP 1 LAST PART_NUMBER CH31006KB18
J 0
(-725 6425);
DISPLAY 0.319149 (-725 6425);
DISPLAY INVISIBLE (-725 6425);
FORCEPROP 1 LAST PACK_TYPE C0402
J 0
(-725 6375);
DISPLAY 0.510638 (-725 6375);
FORCEPROP 1 LAST MATERIAL X7R
J 0
(-725 6475);
DISPLAY 0.510638 (-725 6475);
FORCEPROP 1 LAST TOLERANCE 10%
J 0
(-725 6525);
DISPLAY 0.510638 (-725 6525);
FORCEPROP 1 LAST VALUE 0.01UF
J 0
(-725 6625);
DISPLAY 0.510638 (-725 6625);
FORCEPROP 1 LAST VOLTAGE 50V
J 0
(-725 6575);
DISPLAY 0.510638 (-725 6575);
FORCEPROP 1 LAST LOCATION C2287
J 0
(-725 6675);
DISPLAY 0.638298 (-725 6675);
FORCEPROP 1 LASTPIN (-775 6675) $PN 1
J 0
(-765 6655);
DISPLAY 0.787234 (-765 6655);
PAINT MONO (-765 6655);
FORCEPROP 1 LASTPIN (-775 6475) $PN 2
J 0
(-765 6455);
DISPLAY 0.787234 (-765 6455);
PAINT MONO (-765 6455);
FORCEPROP 2 LAST CDS_LIB pure_quanta
J 0
(-775 6575);
DISPLAY INVISIBLE (-775 6575);
FORCEPROP 1 LAST PATH I36
J 0
(-725 6725);
DISPLAY 0.978723 (-725 6725);
PAINT WHITE (-725 6725);
DISPLAY INVISIBLE (-725 6725);
FORCEPROP 0 LAST $SEC 1
J 0
(-725 6725);
DISPLAY 0.680851 (-725 6725);
PAINT MONO (-725 6725);
DISPLAY INVISIBLE (-725 6725);
FORCEPROP 0 LAST CDS_SEC 1
J 0
(-725 6725);
DISPLAY 1.021277 (-725 6725);
DISPLAY INVISIBLE (-725 6725);
FORCEADD Q_CAP..1
(-150 6050);
FORCEPROP 1 LAST PART_NUMBER CH622KMEA03
J 0
(-100 5900);
DISPLAY 0.617021 (-100 5900);
PAINT BLUE (-100 5900);
DISPLAY INVISIBLE (-100 5900);
FORCEPROP 1 LAST VALUE 22UF
J 0
(-100 6100);
DISPLAY 0.617021 (-100 6100);
PAINT SKYBLUE (-100 6100);
FORCEPROP 1 LAST TOLERANCE 20%
J 0
(-100 6000);
DISPLAY 0.617021 (-100 6000);
PAINT SKYBLUE (-100 6000);
FORCEPROP 1 LAST MATERIAL X6S
J 0
(-100 5950);
DISPLAY 0.617021 (-100 5950);
PAINT SKYBLUE (-100 5950);
FORCEPROP 1 LAST PACK_TYPE C0805
J 0
(-100 5850);
DISPLAY 0.617021 (-100 5850);
PAINT SKYBLUE (-100 5850);
FORCEPROP 1 LAST VOLTAGE 4V
J 0
(-100 6050);
DISPLAY 0.617021 (-100 6050);
PAINT SKYBLUE (-100 6050);
FORCEPROP 1 LAST LOCATION PC1238
J 0
(-100 6150);
DISPLAY 0.617021 (-100 6150);
PAINT AQUA (-100 6150);
FORCEPROP 1 LASTPIN (-150 6150) $PN 1
J 0
(-140 6130);
DISPLAY 0.617021 (-140 6130);
FORCEPROP 1 LASTPIN (-150 5950) $PN 2
J 0
(-140 5930);
DISPLAY 0.617021 (-140 5930);
FORCEPROP 2 LAST CDS_LIB pure_quanta
J 0
(-150 6050);
PAINT MONO (-150 6050);
DISPLAY INVISIBLE (-150 6050);
FORCEPROP 2 LAST BOM_COST VR_PCH
J 0
(-100 6200);
DISPLAY 0.680851 (-100 6200);
DISPLAY INVISIBLE (-100 6200);
FORCEPROP 1 LAST PATH I37
J 0
(-100 6200);
DISPLAY 0.978723 (-100 6200);
PAINT WHITE (-100 6200);
DISPLAY INVISIBLE (-100 6200);
FORCEPROP 2 LAST $SEC 1
J 0
(-100 6250);
DISPLAY 0.680851 (-100 6250);
PAINT MONO (-100 6250);
DISPLAY INVISIBLE (-100 6250);
FORCEPROP 2 LAST CDS_SEC 1
J 0
(-100 6250);
DISPLAY 1.021277 (-100 6250);
DISPLAY INVISIBLE (-100 6250);
FORCEADD Q_CAP..1
(225 6050);
FORCEPROP 1 LAST PART_NUMBER CH622KMEA03
J 0
(275 5900);
DISPLAY 0.617021 (275 5900);
PAINT BLUE (275 5900);
DISPLAY INVISIBLE (275 5900);
FORCEPROP 1 LAST VALUE 22UF
J 0
(275 6100);
DISPLAY 0.617021 (275 6100);
PAINT SKYBLUE (275 6100);
FORCEPROP 1 LAST PACK_TYPE C0805
J 0
(275 5850);
DISPLAY 0.617021 (275 5850);
PAINT SKYBLUE (275 5850);
FORCEPROP 1 LAST MATERIAL X6S
J 0
(275 5950);
DISPLAY 0.617021 (275 5950);
PAINT SKYBLUE (275 5950);
FORCEPROP 1 LAST VOLTAGE 4V
J 0
(275 6050);
DISPLAY 0.617021 (275 6050);
PAINT SKYBLUE (275 6050);
FORCEPROP 1 LAST TOLERANCE 20%
J 0
(275 6000);
DISPLAY 0.617021 (275 6000);
PAINT SKYBLUE (275 6000);
FORCEPROP 1 LAST LOCATION PC1239
J 0
(275 6150);
DISPLAY 0.617021 (275 6150);
PAINT AQUA (275 6150);
FORCEPROP 1 LASTPIN (225 6150) $PN 1
J 0
(235 6130);
DISPLAY 0.617021 (235 6130);
FORCEPROP 1 LASTPIN (225 5950) $PN 2
J 0
(235 5930);
DISPLAY 0.617021 (235 5930);
FORCEPROP 2 LAST CDS_LIB pure_quanta
J 0
(225 6050);
PAINT MONO (225 6050);
DISPLAY INVISIBLE (225 6050);
FORCEPROP 2 LAST BOM_COST VR_PCH
J 0
(275 6200);
DISPLAY 0.680851 (275 6200);
DISPLAY INVISIBLE (275 6200);
FORCEPROP 1 LAST PATH I38
J 0
(275 6200);
DISPLAY 0.978723 (275 6200);
PAINT WHITE (275 6200);
DISPLAY INVISIBLE (275 6200);
FORCEPROP 2 LAST $SEC 1
J 0
(275 6250);
DISPLAY 0.680851 (275 6250);
PAINT MONO (275 6250);
DISPLAY INVISIBLE (275 6250);
FORCEPROP 2 LAST CDS_SEC 1
J 0
(275 6250);
DISPLAY 1.021277 (275 6250);
DISPLAY INVISIBLE (275 6250);
FORCEADD Q_CAP..1
(600 6050);
FORCEPROP 1 LAST PART_NUMBER CH622KMEA03
J 0
(650 5900);
DISPLAY 0.617021 (650 5900);
PAINT BLUE (650 5900);
DISPLAY INVISIBLE (650 5900);
FORCEPROP 1 LAST MATERIAL X6S
J 0
(650 5950);
DISPLAY 0.617021 (650 5950);
PAINT SKYBLUE (650 5950);
FORCEPROP 1 LAST TOLERANCE 20%
J 0
(650 6000);
DISPLAY 0.617021 (650 6000);
PAINT SKYBLUE (650 6000);
FORCEPROP 1 LAST VALUE 22UF
J 0
(650 6100);
DISPLAY 0.617021 (650 6100);
PAINT SKYBLUE (650 6100);
FORCEPROP 1 LAST PACK_TYPE C0805
J 0
(650 5850);
DISPLAY 0.617021 (650 5850);
PAINT SKYBLUE (650 5850);
FORCEPROP 1 LAST VOLTAGE 4V
J 0
(650 6050);
DISPLAY 0.617021 (650 6050);
PAINT SKYBLUE (650 6050);
FORCEPROP 1 LAST LOCATION PC1240
J 0
(650 6150);
DISPLAY 0.617021 (650 6150);
PAINT AQUA (650 6150);
FORCEPROP 1 LASTPIN (600 6150) $PN 1
J 0
(610 6130);
DISPLAY 0.617021 (610 6130);
FORCEPROP 1 LASTPIN (600 5950) $PN 2
J 0
(610 5930);
DISPLAY 0.617021 (610 5930);
FORCEPROP 2 LAST BOM_COST VR_PCH
J 0
(650 6200);
DISPLAY 0.680851 (650 6200);
DISPLAY INVISIBLE (650 6200);
FORCEPROP 2 LAST CDS_LIB pure_quanta
J 0
(600 6050);
PAINT MONO (600 6050);
DISPLAY INVISIBLE (600 6050);
FORCEPROP 1 LAST PATH I39
J 0
(650 6200);
DISPLAY 0.978723 (650 6200);
PAINT WHITE (650 6200);
DISPLAY INVISIBLE (650 6200);
FORCEPROP 2 LAST $SEC 1
J 0
(650 6250);
DISPLAY 0.680851 (650 6250);
PAINT MONO (650 6250);
DISPLAY INVISIBLE (650 6250);
FORCEPROP 2 LAST CDS_SEC 1
J 0
(650 6250);
DISPLAY 1.021277 (650 6250);
DISPLAY INVISIBLE (650 6250);
FORCEADD Q_CAP..1
(-5750 5175);
FORCEPROP 1 LAST PART_NUMBER CH5104KEB02
J 0
(-5700 5025);
DISPLAY 0.617021 (-5700 5025);
PAINT BLUE (-5700 5025);
DISPLAY INVISIBLE (-5700 5025);
FORCEPROP 1 LAST PACK_TYPE C0402
J 0
(-5700 4975);
DISPLAY 0.617021 (-5700 4975);
PAINT SKYBLUE (-5700 4975);
FORCEPROP 1 LAST VOLTAGE 25V
J 0
(-5700 5175);
DISPLAY 0.617021 (-5700 5175);
PAINT SKYBLUE (-5700 5175);
FORCEPROP 1 LAST MATERIAL X6S
J 0
(-5700 5075);
DISPLAY 0.617021 (-5700 5075);
PAINT SKYBLUE (-5700 5075);
FORCEPROP 1 LAST TOLERANCE 10%
J 0
(-5700 5125);
DISPLAY 0.617021 (-5700 5125);
PAINT SKYBLUE (-5700 5125);
FORCEPROP 1 LAST VALUE 1UF
J 0
(-5700 5225);
DISPLAY 0.617021 (-5700 5225);
PAINT SKYBLUE (-5700 5225);
FORCEPROP 1 LAST LOCATION PC1642
J 0
(-5700 5275);
DISPLAY 0.617021 (-5700 5275);
PAINT AQUA (-5700 5275);
FORCEPROP 1 LASTPIN (-5750 5275) $PN 1
J 0
(-5740 5255);
DISPLAY 0.617021 (-5740 5255);
FORCEPROP 1 LASTPIN (-5750 5075) $PN 2
J 0
(-5740 5055);
DISPLAY 0.617021 (-5740 5055);
FORCEPROP 2 LAST CDS_LIB pure_quanta
J 0
(-5750 5175);
DISPLAY INVISIBLE (-5750 5175);
FORCEPROP 2 LAST SEC_TYPE C0402
J 0
(-5700 5375);
DISPLAY 1.021277 (-5700 5375);
DISPLAY INVISIBLE (-5700 5375);
FORCEPROP 2 LAST BOM_COST VR_PCH
J 0
(-5700 5325);
DISPLAY 0.680851 (-5700 5325);
DISPLAY INVISIBLE (-5700 5325);
FORCEPROP 1 LAST PATH I4
J 0
(-5700 5325);
DISPLAY 0.978723 (-5700 5325);
PAINT WHITE (-5700 5325);
DISPLAY INVISIBLE (-5700 5325);
FORCEPROP 2 LAST SEC 1
J 0
(-5700 5375);
DISPLAY 0.680851 (-5700 5375);
PAINT MONO (-5700 5375);
DISPLAY INVISIBLE (-5700 5375);
FORCEADD UNIVERSAL_GND..1
(1100 5675);
FORCEPROP 3 LASTPIN (1100 5725) SIG_NAME GND\g
J 0
(1110 5735);
DISPLAY 0.659574 (1110 5735);
PAINT MONO (1110 5735);
DISPLAY INVISIBLE (1110 5735);
FORCEPROP 2 LAST CDS_LIB logical_power
J 0
(1100 5675);
DISPLAY INVISIBLE (1100 5675);
FORCEPROP 1 LAST HDL_POWER GND
J 1
(1125 5600);
DISPLAY 0.872340 (1125 5600);
PAINT GREEN (1125 5600);
DISPLAY INVISIBLE (1125 5600);
FORCEPROP 1 LAST PATH I40
J 0
(1175 5675);
DISPLAY 0.872340 (1175 5675);
PAINT AQUA (1175 5675);
DISPLAY INVISIBLE (1175 5675);
FORCEADD Q_CAP..1
(975 6050);
FORCEPROP 1 LAST PART_NUMBER CH622KMEA03
J 0
(1025 5900);
DISPLAY 0.617021 (1025 5900);
PAINT BLUE (1025 5900);
DISPLAY INVISIBLE (1025 5900);
FORCEPROP 1 LAST VOLTAGE 4V
J 0
(1025 6050);
DISPLAY 0.617021 (1025 6050);
PAINT SKYBLUE (1025 6050);
FORCEPROP 1 LAST VALUE 22UF
J 0
(1025 6100);
DISPLAY 0.617021 (1025 6100);
PAINT SKYBLUE (1025 6100);
FORCEPROP 1 LAST PACK_TYPE C0805
J 0
(1025 5850);
DISPLAY 0.617021 (1025 5850);
PAINT SKYBLUE (1025 5850);
FORCEPROP 1 LAST TOLERANCE 20%
J 0
(1025 6000);
DISPLAY 0.617021 (1025 6000);
PAINT SKYBLUE (1025 6000);
FORCEPROP 1 LAST MATERIAL X6S
J 0
(1025 5950);
DISPLAY 0.617021 (1025 5950);
PAINT SKYBLUE (1025 5950);
FORCEPROP 1 LAST LOCATION PC1241
J 0
(1025 6150);
DISPLAY 0.617021 (1025 6150);
PAINT AQUA (1025 6150);
FORCEPROP 1 LASTPIN (975 6150) $PN 1
J 0
(985 6130);
DISPLAY 0.617021 (985 6130);
FORCEPROP 1 LASTPIN (975 5950) $PN 2
J 0
(985 5930);
DISPLAY 0.617021 (985 5930);
FORCEPROP 2 LAST BOM_COST VR_PCH
J 0
(1025 6200);
DISPLAY 0.680851 (1025 6200);
DISPLAY INVISIBLE (1025 6200);
FORCEPROP 2 LAST CDS_LIB pure_quanta
J 0
(975 6050);
PAINT MONO (975 6050);
DISPLAY INVISIBLE (975 6050);
FORCEPROP 1 LAST PATH I41
J 0
(1025 6200);
DISPLAY 0.978723 (1025 6200);
PAINT WHITE (1025 6200);
DISPLAY INVISIBLE (1025 6200);
FORCEPROP 2 LAST $SEC 1
J 0
(1025 6250);
DISPLAY 0.680851 (1025 6250);
PAINT MONO (1025 6250);
DISPLAY INVISIBLE (1025 6250);
FORCEPROP 2 LAST CDS_SEC 1
J 0
(1025 6250);
DISPLAY 1.021277 (1025 6250);
DISPLAY INVISIBLE (1025 6250);
FORCEADD Q_RES..2
(1375 6025);
FORCEPROP 1 LAST PART_NUMBER CS14702FB04
J 0
(1415 5900);
DISPLAY 0.638298 (1415 5900);
DISPLAY INVISIBLE (1415 5900);
FORCEPROP 1 LAST TOLERANCE 1%
J 0
(1420 6050);
DISPLAY 0.638298 (1420 6050);
FORCEPROP 1 LAST WATTAGE 1/16W
J 0
(1415 6000);
DISPLAY 0.638298 (1415 6000);
FORCEPROP 1 LAST PACK_TYPE 0402LF
J 0
(1415 5850);
DISPLAY 0.638298 (1415 5850);
FORCEPROP 1 LAST MATERIAL CHIP
J 0
(1415 5950);
DISPLAY 0.638298 (1415 5950);
FORCEPROP 1 LAST VALUE 470
J 0
(1420 6100);
DISPLAY 0.638298 (1420 6100);
FORCEPROP 1 LAST LOCATION PR1653
J 0
(1420 6150);
DISPLAY 0.638298 (1420 6150);
FORCEPROP 1 LASTPIN (1375 6125) $PN 1
J 0
(1380 6087);
DISPLAY 0.787234 (1380 6087);
PAINT MONO (1380 6087);
FORCEPROP 1 LASTPIN (1375 5925) $PN 2
J 0
(1380 5935);
DISPLAY 0.787234 (1380 5935);
PAINT MONO (1380 5935);
FORCEPROP 2 LAST CDS_LIB pure_quanta
J 0
(1375 6025);
DISPLAY INVISIBLE (1375 6025);
FORCEPROP 1 LAST PATH I42
J 0
(1425 6200);
DISPLAY 0.978723 (1425 6200);
PAINT WHITE (1425 6200);
DISPLAY INVISIBLE (1425 6200);
FORCEPROP 0 LAST $SEC 1
J 0
(1425 6200);
DISPLAY 0.680851 (1425 6200);
PAINT MONO (1425 6200);
DISPLAY INVISIBLE (1425 6200);
FORCEPROP 0 LAST CDS_SEC 1
J 0
(1425 6200);
DISPLAY 1.021277 (1425 6200);
DISPLAY INVISIBLE (1425 6200);
FORCEADD OFFPAGE..2
(75 6750);
FORCEPROP 2 LAST $XR2 252 
J 0
(504 6750);
DISPLAY 0.638298 (504 6750);
PAINT MONO (504 6750);
FORCEPROP 2 LAST $XR1 222 
J 0
(384 6750);
DISPLAY 0.638298 (384 6750);
PAINT MONO (384 6750);
FORCEPROP 2 LAST $XR0 194 
J 0
(264 6750);
DISPLAY 0.638298 (264 6750);
PAINT MONO (264 6750);
FORCEPROP 2 LAST CDS_LIB standard
J 0
(75 6750);
PAINT MONO (75 6750);
DISPLAY INVISIBLE (75 6750);
FORCEPROP 2 LAST BOM_COST VR_SYSTEM 
J 0
(425 6800);
DISPLAY 0.680851 (425 6800);
DISPLAY INVISIBLE (425 6800);
FORCEPROP 1 LAST OFFPAGE TRUE
J 0
(400 6625);
DISPLAY 0.531915 (400 6625);
PAINT GREEN (400 6625);
DISPLAY INVISIBLE (400 6625);
FORCEPROP 1 LAST COMMENT_BODY TRUE
J 0
(30 6655);
DISPLAY 0.531915 (30 6655);
PAINT GREEN (30 6655);
DISPLAY INVISIBLE (30 6655);
FORCEPROP 2 LAST PATH I43
J 0
(525 6800);
DISPLAY 1.021277 (525 6800);
DISPLAY INVISIBLE (525 6800);
FORCEADD UNIVERSAL_POWER..1
(1775 6475);
FORCEPROP 3 LASTPIN (1775 6425) SIG_NAME P1V8_PCH_AUX\g
J 0
(1785 6435);
DISPLAY 0.659574 (1785 6435);
PAINT MONO (1785 6435);
DISPLAY INVISIBLE (1785 6435);
FORCEPROP 1 LAST HDL_POWER P1V8_PCH_AUX
J 1
(1775 6525);
DISPLAY 0.617021 (1775 6525);
PAINT GREEN (1775 6525);
FORCEPROP 2 LAST CDS_LIB logical_power
J 0
(1775 6475);
DISPLAY INVISIBLE (1775 6475);
FORCEPROP 1 LAST PATH I44
J 0
(1825 6500);
DISPLAY 0.872340 (1825 6500);
PAINT AQUA (1825 6500);
DISPLAY INVISIBLE (1825 6500);
FORCEADD Q_INDUCTOR..1
(-1175 6275);
FORCEPROP 1 LAST PART_NUMBER CV-2280MZ15
J 0
(-1300 6385);
DISPLAY 0.723404 (-1300 6385);
PAINT GREEN (-1300 6385);
DISPLAY INVISIBLE (-1300 6385);
FORCEPROP 1 LAST MATERIAL IND
J 0
(-1300 6330);
DISPLAY 0.723404 (-1300 6330);
PAINT GREEN (-1300 6330);
FORCEPROP 2 LAST PACK_TYPE SMLF
J 0
(-1300 6550);
DISPLAY 0.617021 (-1300 6550);
PAINT SKYBLUE (-1300 6550);
FORCEPROP 2 LAST VALUE 2.2UH
J 0
(-1300 6500);
DISPLAY 0.617021 (-1300 6500);
PAINT SKYBLUE (-1300 6500);
FORCEPROP 1 LAST LOCATION PL170
J 0
(-1300 6435);
DISPLAY 0.723404 (-1300 6435);
PAINT GREEN (-1300 6435);
FORCEPROP 0 LASTPIN (-1275 6250) $PN 1
J 2
(-1285 6260);
DISPLAY 0.680851 (-1285 6260);
PAINT MONO (-1285 6260);
FORCEPROP 0 LASTPIN (-1075 6250) $PN 2
J 0
(-1065 6260);
DISPLAY 0.680851 (-1065 6260);
PAINT MONO (-1065 6260);
FORCEPROP 2 LAST BOM_COST VR_PCH
J 0
(-1300 6575);
DISPLAY 0.680851 (-1300 6575);
DISPLAY INVISIBLE (-1300 6575);
FORCEPROP 1 LAST NEEDS_NO_SIZE TRUE
J 0
(-1175 6275);
DISPLAY 0.468085 (-1175 6275);
PAINT GREEN (-1175 6275);
DISPLAY INVISIBLE (-1175 6275);
FORCEPROP 1 LAST PATH I45
J 0
(-1100 6330);
DISPLAY 0.723404 (-1100 6330);
PAINT GREEN (-1100 6330);
DISPLAY INVISIBLE (-1100 6330);
FORCEPROP 2 LAST CDS_LIB pure_quanta
J 0
(-1175 6275);
DISPLAY INVISIBLE (-1175 6275);
FORCEPROP 0 LAST $SEC 1
J 0
(-1300 6600);
DISPLAY 0.680851 (-1300 6600);
PAINT MONO (-1300 6600);
DISPLAY INVISIBLE (-1300 6600);
FORCEPROP 0 LAST CDS_SEC 1
J 0
(-1300 6600);
DISPLAY 1.021277 (-1300 6600);
DISPLAY INVISIBLE (-1300 6600);
FORCEADD Q_RES..2
(-5750 5600);
FORCEPROP 1 LAST PART_NUMBER CS-5102JB02
J 0
(-5710 5475);
DISPLAY 0.617021 (-5710 5475);
PAINT BLUE (-5710 5475);
DISPLAY INVISIBLE (-5710 5475);
FORCEPROP 1 LAST TOLERANCE 5%
J 0
(-5705 5625);
DISPLAY 0.617021 (-5705 5625);
PAINT SKYBLUE (-5705 5625);
FORCEPROP 1 LAST VALUE 5.1
J 0
(-5705 5675);
DISPLAY 0.617021 (-5705 5675);
PAINT SKYBLUE (-5705 5675);
FORCEPROP 1 LAST PACK_TYPE 0402LF
J 0
(-5710 5425);
DISPLAY 0.617021 (-5710 5425);
PAINT SKYBLUE (-5710 5425);
FORCEPROP 1 LAST WATTAGE 1/16W
J 0
(-5710 5575);
DISPLAY 0.617021 (-5710 5575);
PAINT SKYBLUE (-5710 5575);
FORCEPROP 1 LAST MATERIAL CHIP
J 0
(-5710 5525);
DISPLAY 0.617021 (-5710 5525);
PAINT SKYBLUE (-5710 5525);
FORCEPROP 1 LAST LOCATION PR1329
J 0
(-5705 5725);
DISPLAY 0.617021 (-5705 5725);
PAINT AQUA (-5705 5725);
FORCEPROP 1 LASTPIN (-5750 5700) $PN 1
J 0
(-5745 5662);
DISPLAY 0.617021 (-5745 5662);
FORCEPROP 1 LASTPIN (-5750 5500) $PN 2
J 0
(-5745 5510);
DISPLAY 0.617021 (-5745 5510);
FORCEPROP 2 LAST CDS_LIB pure_quanta
J 0
(-5750 5600);
PAINT MONO (-5750 5600);
DISPLAY INVISIBLE (-5750 5600);
FORCEPROP 1 LAST PATH I5
J 0
(-5700 5775);
DISPLAY 0.978723 (-5700 5775);
PAINT WHITE (-5700 5775);
DISPLAY INVISIBLE (-5700 5775);
FORCEPROP 2 LAST $SEC 1
J 0
(-5700 5825);
DISPLAY 0.680851 (-5700 5825);
PAINT MONO (-5700 5825);
DISPLAY INVISIBLE (-5700 5825);
FORCEPROP 2 LAST CDS_SEC 1
J 0
(-5700 5825);
DISPLAY 1.021277 (-5700 5825);
DISPLAY INVISIBLE (-5700 5825);
FORCEADD UNIVERSAL_POWER..1
(-5750 5825);
FORCEPROP 3 LASTPIN (-5750 5775) SIG_NAME PVCC1_AUX\g
J 0
(-5740 5785);
DISPLAY 0.659574 (-5740 5785);
PAINT MONO (-5740 5785);
DISPLAY INVISIBLE (-5740 5785);
FORCEPROP 1 LAST HDL_POWER PVCC1_AUX
J 1
(-5750 5875);
DISPLAY 0.617021 (-5750 5875);
PAINT GREEN (-5750 5875);
FORCEPROP 2 LAST CDS_LIB logical_power
J 0
(-5750 5825);
DISPLAY INVISIBLE (-5750 5825);
FORCEPROP 1 LAST PATH I6
J 0
(-5700 5850);
DISPLAY 0.872340 (-5700 5850);
PAINT AQUA (-5700 5850);
DISPLAY INVISIBLE (-5700 5850);
FORCEADD UNIVERSAL_POWER..1
(-5300 4500);
FORCEPROP 3 LASTPIN (-5300 4450) SIG_NAME P3V3_AUX\g
J 0
(-5290 4460);
DISPLAY 0.659574 (-5290 4460);
PAINT MONO (-5290 4460);
DISPLAY INVISIBLE (-5290 4460);
FORCEPROP 1 LAST HDL_POWER P3V3_AUX
J 1
(-5300 4550);
DISPLAY 0.617021 (-5300 4550);
PAINT GREEN (-5300 4550);
FORCEPROP 2 LAST CDS_LIB logical_power
J 0
(-5300 4500);
DISPLAY INVISIBLE (-5300 4500);
FORCEPROP 1 LAST PATH I7
J 0
(-5250 4525);
DISPLAY 0.872340 (-5250 4525);
PAINT AQUA (-5250 4525);
DISPLAY INVISIBLE (-5250 4525);
FORCEADD Q_RES..1
(-4750 4375);
FORCEPROP 1 LAST PART_NUMBER CS00002JB13
J 0
(-4800 4475);
DISPLAY 0.617021 (-4800 4475);
PAINT BLUE (-4800 4475);
DISPLAY INVISIBLE (-4800 4475);
FORCEPROP 1 LAST MATERIAL CHIP
J 0
(-4750 4225);
DISPLAY 0.617021 (-4750 4225);
PAINT SKYBLUE (-4750 4225);
FORCEPROP 1 LAST VALUE 0
J 2
(-4775 4275);
DISPLAY 0.617021 (-4775 4275);
PAINT SKYBLUE (-4775 4275);
FORCEPROP 1 LAST PACK_TYPE 0402LF
J 0
(-4500 4225);
DISPLAY 0.617021 (-4500 4225);
PAINT SKYBLUE (-4500 4225);
FORCEPROP 1 LAST WATTAGE 1/16W
J 2
(-4775 4225);
DISPLAY 0.617021 (-4775 4225);
PAINT SKYBLUE (-4775 4225);
FORCEPROP 1 LAST TOLERANCE 5%
J 0
(-4750 4275);
DISPLAY 0.617021 (-4750 4275);
PAINT SKYBLUE (-4750 4275);
FORCEPROP 1 LAST LOCATION PR395
J 0
(-4800 4425);
DISPLAY 0.617021 (-4800 4425);
PAINT AQUA (-4800 4425);
FORCEPROP 2 LAST CDS_LIB pure_quanta
J 0
(-4750 4375);
DISPLAY INVISIBLE (-4750 4375);
FORCEPROP 1 LAST PATH I8
J 0
(-4800 4525);
DISPLAY 0.978723 (-4800 4525);
PAINT WHITE (-4800 4525);
DISPLAY INVISIBLE (-4800 4525);
FORCEPROP 0 LAST $SEC 1
J 0
(-4800 4525);
DISPLAY INVISIBLE (-4800 4525);
FORCEPROP 0 LAST CDS_SEC 1
J 0
(-4800 4525);
DISPLAY INVISIBLE (-4800 4525);
FORCEPROP 1 LASTPIN (-4850 4375) $PN 1
J 0
(-4838 4387);
DISPLAY 0.787234 (-4838 4387);
PAINT MONO (-4838 4387);
DISPLAY INVISIBLE (-4838 4387);
FORCEPROP 1 LASTPIN (-4650 4375) $PN 2
J 0
(-4688 4387);
DISPLAY 0.787234 (-4688 4387);
PAINT MONO (-4688 4387);
DISPLAY INVISIBLE (-4688 4387);
FORCEADD UNIVERSAL_GND..1
(-4600 4900);
FORCEPROP 3 LASTPIN (-4600 4950) SIG_NAME GND\g
J 0
(-4590 4960);
DISPLAY 0.659574 (-4590 4960);
PAINT MONO (-4590 4960);
DISPLAY INVISIBLE (-4590 4960);
FORCEPROP 2 LAST CDS_LIB logical_power
J 0
(-4600 4900);
PAINT MONO (-4600 4900);
DISPLAY INVISIBLE (-4600 4900);
FORCEPROP 1 LAST HDL_POWER GND
J 1
(-4575 4825);
DISPLAY 0.872340 (-4575 4825);
PAINT GREEN (-4575 4825);
DISPLAY INVISIBLE (-4575 4825);
FORCEPROP 1 LAST PATH I9
J 0
(-4525 4900);
DISPLAY 0.872340 (-4525 4900);
PAINT AQUA (-4525 4900);
DISPLAY INVISIBLE (-4525 4900);
FORCEADD DNS..2
(-4775 3950);
PAINT RED (-4775 3950);
FORCEPROP 2 LAST CDS_LIB mstr_misc
J 0
(-4775 3950);
DISPLAY INVISIBLE (-4775 3950);
FORCEPROP 1 LAST COMMENT_BODY TRUE
R 1
J 0
(-4700 3725);
DISPLAY 0.872340 (-4700 3725);
PAINT GREEN (-4700 3725);
DISPLAY INVISIBLE (-4700 3725);
FORCEADD DNS..2
(-4475 5950);
PAINT RED (-4475 5950);
FORCEPROP 2 LAST CDS_LIB mstr_misc
J 0
(-4475 5950);
PAINT MONO (-4475 5950);
DISPLAY INVISIBLE (-4475 5950);
FORCEPROP 1 LAST COMMENT_BODY TRUE
R 1
J 0
(-4400 5725);
DISPLAY 0.872340 (-4400 5725);
PAINT GREEN (-4400 5725);
DISPLAY INVISIBLE (-4400 5725);
FORCEADD CAD_NOTE..1
(-6250 6525);
FORCEPROP 0 LAST L1 CAP & DAMPING RS CLOSE TO DRIVE-END
J 0
(-6400 6425);
DISPLAY 0.680851 (-6400 6425);
PAINT SKYBLUE (-6400 6425);
FORCEPROP 2 LAST BOM_COST VR_PCH
J 0
(-6675 6450);
DISPLAY 0.680851 (-6675 6450);
DISPLAY INVISIBLE (-6675 6450);
FORCEPROP 2 LAST CDS_LIB logical_power
J 0
(-6250 6525);
DISPLAY INVISIBLE (-6250 6525);
FORCEPROP 1 LAST COMMENT_BODY TRUE
J 0
(-6225 6625);
DISPLAY 0.978723 (-6225 6625);
DISPLAY INVISIBLE (-6225 6625);
FORCEADD CAD_NOTE..1
(-1125 7100);
FORCEPROP 0 LAST L1 CAP & DAMPING RS CLOSE TO DRIVE-END
J 0
(-1275 7000);
DISPLAY 0.680851 (-1275 7000);
PAINT SKYBLUE (-1275 7000);
FORCEPROP 2 LAST BOM_COST VR_PCH
J 0
(-1550 7025);
DISPLAY 0.680851 (-1550 7025);
DISPLAY INVISIBLE (-1550 7025);
FORCEPROP 2 LAST CDS_LIB logical_power
J 0
(-1125 7100);
DISPLAY INVISIBLE (-1125 7100);
FORCEPROP 1 LAST COMMENT_BODY TRUE
J 0
(-1100 7200);
DISPLAY 0.978723 (-1100 7200);
DISPLAY INVISIBLE (-1100 7200);
FORCEADD QUANTA_TITLE_BLOCK_C..1
(2200 3050);
FORCEPROP 0 LAST CDS_CON_LAST_MODIFIED Fri Aug 25 14:04:34 2023
J 0
(315 3065);
DISPLAY INVISIBLE (315 3065);
FORCEPROP 1 LAST CUSTOM_TXT_CDS <CON_LAST_MODIFIED>
J 0
(315 3065);
DISPLAY 0.978723 (315 3065);
FORCEPROP 2 LAST CUSTOM_TXT_CDS <XR_PAGE_TITLE>
J 0
(-5690 8300);
DISPLAY 0.638298 (-5690 8300);
PAINT PINK (-5690 8300);
DISPLAY INVISIBLE (-5690 8300);
FORCEPROP 1 LAST CUSTOM_TXT_CDS <NAME_2>
J 0
(-975 3100);
FORCEPROP 1 LAST CUSTOM_TXT_CDS <NAME_1>
J 0
(-975 3225);
FORCEPROP 1 LAST CUSTOM_TXT_CDS <Q_NUMBER>
J 0
(797 3153);
DISPLAY 1.212766 (797 3153);
FORCEPROP 1 LAST CUSTOM_TXT_CDS <Q_PROJ>
J 0
(-182 3152);
DISPLAY 1.212766 (-182 3152);
FORCEPROP 1 LAST CUSTOM_TXT_CDS <Q_REV>
J 0
(2016 3153);
DISPLAY 1.212766 (2016 3153);
FORCEPROP 1 LAST CUSTOM_TXT_CDS <CON_PAGE_NUM> OF <CON_TOTAL_PAGES>
J 0
(1754 3068);
DISPLAY 0.978723 (1754 3068);
FORCEPROP 1 LAST Q_TITLE NB695/P1V8_PCH_AUX
J 0
(-7100 3125);
DISPLAY 2.446809 (-7100 3125);
PAINT GREEN (-7100 3125);
FORCEPROP 1 LAST Q_DEPT 
J 1
(-1563 3099);
DISPLAY 1.957447 (-1563 3099);
PAINT GREEN (-1563 3099);
FORCEPROP 2 LAST CDS_XR_PAGE_TITLE CR-263 : @S9S_MB_2U_LIB.S9S_MB_2U(SCH_1):PAGE263
J 0
(-5690 8300);
DISPLAY 0.638298 (-5690 8300);
PAINT PINK (-5690 8300);
DISPLAY INVISIBLE (-5690 8300);
FORCEPROP 1 LAST COMMENT_BODY TRUE
J 0
(2212 3037);
DISPLAY 0.978723 (2212 3037);
PAINT GREEN (2212 3037);
DISPLAY INVISIBLE (2212 3037);
FORCEPROP 2 LAST PAGE_BORDER TRUE
J 0
(-5690 8300);
DISPLAY 0.638298 (-5690 8300);
PAINT PINK (-5690 8300);
DISPLAY INVISIBLE (-5690 8300);
FORCEPROP 1 LAST CDS_LMAN_SYM_OUTLINE -9475,6775,100,-125
J 0
(2200 3050);
DISPLAY 0.468085 (2200 3050);
PAINT GREEN (2200 3050);
DISPLAY INVISIBLE (2200 3050);
FORCEPROP 2 LAST CDS_LIB pure_quanta
J 0
(2200 3050);
DISPLAY INVISIBLE (2200 3050);
WIRE 16 -1 (-5300 4025)(-5300 3950);
WIRE 16 -1 (-5750 5700)(-5750 5775);
WIRE 16 -1 (-5300 4375)(-5300 4450);
WIRE 16 -1 (-5300 4375)(-4850 4375);
WIRE 16 -1 (-6350 7225)(-6350 7375);
WIRE 16 -1 (-6350 7225)(-6075 7225);
WIRE 16 -1 (-6350 7125)(-6350 7225);
WIRE 16 -1 (-4150 4050)(-4150 3950);
WIRE 16 -1 (-4150 4450)(-4150 4375);
WIRE 16 -1 (-1875 7225)(-1875 7325);
WIRE 16 -1 (1775 6425)(1775 6250);
WIRE 16 -1 (-5750 5075)(-5750 4950);
WIRE 16 -1 (-4600 5550)(-4600 4950);
WIRE 16 -1 (-4600 5550)(-3550 5550);
WIRE 16 -1 (-4850 5850)(-4850 5950);
WIRE 16 -1 (-6350 6825)(-6350 6925);
WIRE 16 -1 (-5475 6825)(-5475 6750);
WIRE 16 -1 (-5025 6825)(-5475 6825);
WIRE 16 -1 (-5475 6950)(-5475 6825);
WIRE 16 -1 (-4325 5050)(-4325 4950);
WIRE 16 -1 (-2650 5000)(-2650 5400);
WIRE 16 -1 (-775 6475)(-775 6375);
WIRE 16 -1 (1100 5825)(1100 5725);
WIRE 16 -1 (1100 5825)(975 5825);
WIRE 16 -1 (1375 5825)(1100 5825);
WIRE 16 -1 (-5750 5350)(-5750 5275);
WIRE 16 -1 (-5750 5500)(-5750 5350);
WIRE 16 -1 (-4850 5350)(-5750 5350);
FORCEPROP 2 LAST SIG_NAME P1V8_PCH_AUX_VCC
J 0
(-5410 5360);
DISPLAY 0.617021 (-5410 5360);
WIRE 16 -1 (-4850 5350)(-4850 5650);
WIRE 16 -1 (-3550 5650)(-4850 5650);
WIRE 16 -1 (-3550 6050)(-3900 6050);
WIRE 16 -1 (-3900 5750)(-3900 6050);
WIRE 16 -1 (-3550 5750)(-3900 5750);
WIRE 16 -1 (-4850 5650)(-4850 5750);
WIRE 16 -1 (-4850 5750)(-3900 5750);
WIRE 16 -1 (-1075 6250)(-925 6250);
WIRE 16 -1 (-925 6150)(-925 6250);
WIRE 16 -1 (-925 6250)(-525 6250);
WIRE 16 -1 (-525 6150)(-525 6250);
WIRE 16 -1 (-525 6250)(-150 6250);
WIRE 16 -1 (-150 6150)(-150 6250);
WIRE 16 -1 (-150 6250)(225 6250);
WIRE 16 -1 (225 6150)(225 6250);
WIRE 16 -1 (225 6250)(600 6250);
WIRE 16 -1 (600 6150)(600 6250);
WIRE 16 -1 (600 6250)(975 6250);
WIRE 16 -1 (975 6150)(975 6250);
WIRE 16 -1 (1375 6125)(1375 6250);
WIRE 16 -1 (975 6250)(1375 6250);
WIRE 16 -1 (1375 6250)(1775 6250);
WIRE 16 -1 (1775 6250)(1775 5550);
WIRE 16 -1 (-2750 5550)(1775 5550);
WIRE 16 -1 (-775 6750)(-1225 6750);
WIRE 16 -1 (-775 6675)(-775 6750);
WIRE 16 -1 (25 6750)(-775 6750);
FORCEPROP 2 LAST SIG_NAME PWRGD_P1V8_PCH_AUX
J 0
(-660 6760);
DISPLAY 0.617021 (-660 6760);
WIRE 16 273 (-1300 6950)(-1300 7175);
WIRE 16 273 (-100 7175)(-1300 7175);
WIRE 16 273 (-1300 6950)(-100 6950);
WIRE 16 273 (-100 6950)(-100 7175);
WIRE 16 -1 (-2750 6250)(-1875 6250);
FORCEPROP 2 LAST SIG_NAME SW_P1V8_PCH_AUX_SW
J 0
(-2635 6260);
DISPLAY 0.617021 (-2635 6260);
WIRE 16 -1 (-1875 6250)(-1275 6250);
WIRE 16 -1 (-1875 6375)(-1875 6250);
WIRE 16 -1 (-1875 6575)(-1875 6650);
WIRE 16 -1 (-2675 6650)(-1875 6650);
FORCEPROP 2 LAST SIG_NAME SW_P1V8_PCH_AUX_BST
J 0
(-2635 6660);
DISPLAY 0.617021 (-2635 6660);
WIRE 16 -1 (-2675 6650)(-2675 6550);
WIRE 16 -1 (-2675 6550)(-2750 6550);
WIRE 16 2175 (-178 8400)(1700 8400);
WIRE 16 2175 (1700 9475)(1700 8400);
WIRE 16 2175 (-178 9475)(-178 8400);
WIRE 16 2175 (-178 9475)(1700 9475);
WIRE 16 -1 (1375 5925)(1375 5825);
WIRE 16 -1 (975 5825)(975 5950);
WIRE 16 -1 (600 5825)(600 5950);
WIRE 16 -1 (975 5825)(600 5825);
WIRE 16 -1 (225 5825)(225 5950);
WIRE 16 -1 (600 5825)(225 5825);
WIRE 16 -1 (-150 5950)(-150 5825);
WIRE 16 -1 (-150 5825)(225 5825);
WIRE 16 -1 (-525 5950)(-525 5825);
WIRE 16 -1 (-525 5825)(-150 5825);
WIRE 16 -1 (-925 5825)(-525 5825);
WIRE 16 -1 (-925 5950)(-925 5825);
WIRE 16 -1 (-1875 6750)(-2750 6750);
FORCEPROP 0 LAST CDS_PHYS_NET_NAME PWRGD_P1V8_PCH_AUX_R
J 0
(-2560 6790);
PAINT MONO (-2560 6790);
DISPLAY INVISIBLE (-2560 6790);
FORCEPROP 2 LAST SIG_NAME PWRGD_P1V8_PCH_AUX_R
J 0
(-2560 6760);
DISPLAY 0.617021 (-2560 6760);
WIRE 16 -1 (-1875 7025)(-1875 6750);
WIRE 16 -1 (-1425 6750)(-1875 6750);
WIRE 16 -1 (-3550 6750)(-3725 6750);
WIRE 16 -1 (-3725 6750)(-3725 7225);
WIRE 16 -1 (-4600 7150)(-4600 7225);
WIRE 16 -1 (-3725 7225)(-4600 7225);
FORCEPROP 2 LAST SIG_NAME SW_P1V8_PCH_AUX_FLT
J 0
(-4435 7235);
DISPLAY 0.617021 (-4435 7235);
WIRE 16 -1 (-5025 7150)(-5025 7225);
WIRE 16 -1 (-5025 7225)(-4600 7225);
WIRE 16 -1 (-5875 7225)(-5475 7225);
WIRE 16 -1 (-5025 7225)(-5475 7225);
WIRE 16 -1 (-5475 7150)(-5475 7225);
WIRE 16 -1 (-2750 5400)(-2650 5400);
WIRE 16 -1 (-2650 5450)(-2650 5400);
WIRE 16 -1 (-2750 5450)(-2650 5450);
WIRE 16 -1 (-4400 5950)(-4100 5950);
WIRE 16 -1 (-4100 6250)(-4100 5950);
WIRE 16 -1 (-3550 6250)(-4100 6250);
WIRE 16 -1 (-4900 6250)(-4100 6250);
FORCEPROP 0 LAST CDS_PHYS_NET_NAME FM_PCH_P1V8_AUX_EN_R
J 0
(-4510 6290);
PAINT MONO (-4510 6290);
DISPLAY INVISIBLE (-4510 6290);
FORCEPROP 2 LAST SIG_NAME FM_PCH_P1V8_AUX_EN_R
J 0
(-4360 6260);
DISPLAY 0.617021 (-4360 6260);
WIRE 16 -1 (-4325 5400)(-4325 5250);
WIRE 16 -1 (-3550 5400)(-4325 5400);
FORCEPROP 2 LAST SIG_NAME P1V8_PCH_AUX_MODE
J 0
(-4235 5410);
DISPLAY 0.617021 (-4235 5410);
WIRE 16 -1 (-4150 4375)(-4650 4375);
WIRE 16 -1 (-4150 3950)(-4650 3950);
WIRE 16 -1 (-5025 6950)(-5025 6825);
WIRE 16 -1 (-4600 6825)(-5025 6825);
WIRE 16 -1 (-4600 6950)(-4600 6825);
WIRE 16 273 (-5225 6600)(-6425 6600);
WIRE 16 273 (-5225 6375)(-5225 6600);
WIRE 16 273 (-6425 6375)(-6425 6600);
WIRE 16 273 (-6425 6375)(-5225 6375);
WIRE 16 -1 (-5100 6250)(-6100 6250);
FORCEPROP 0 LAST CDS_PHYS_NET_NAME FM_PCH_P1V8_AUX_EN
J 0
(-6060 6290);
PAINT MONO (-6060 6290);
DISPLAY INVISIBLE (-6060 6290);
FORCEPROP 2 LAST SIG_NAME FM_PCH_P1V8_AUX_EN
J 0
(-6010 6260);
DISPLAY 0.617021 (-6010 6260);
WIRE 16 -1 (-4850 5950)(-4600 5950);
WIRE 16 2175 (-6775 4225)(-5922 4225);
WIRE 16 2175 (-5922 4600)(-5922 4225);
WIRE 16 2175 (-6775 4600)(-6775 4225);
WIRE 16 2175 (-6775 4600)(-5922 4600);
WIRE 16 -1 (-5300 3950)(-4850 3950);
WIRE 16 2175 (-6775 3675)(-5922 3675);
WIRE 16 2175 (-5922 4050)(-5922 3675);
WIRE 16 2175 (-6775 4050)(-6775 3675);
WIRE 16 2175 (-6775 4050)(-5922 4050);
DOT 1 (-1875 6250);
DOT 1 (-5750 5350);
DOT 1 (-4850 5650);
DOT 1 (-6350 7225);
DOT 1 (-5475 6825);
DOT 1 (-5025 6825);
DOT 1 (-5475 7225);
DOT 1 (-5025 7225);
DOT 1 (-4600 7225);
DOT 1 (-3900 5750);
DOT 1 (-2650 5400);
DOT 1 (-4100 6250);
DOT 1 (-525 5825);
DOT 1 (-1875 6750);
DOT 1 (-925 6250);
DOT 1 (-525 6250);
DOT 1 (-775 6750);
DOT 1 (-150 5825);
DOT 1 (225 5825);
DOT 1 (600 5825);
DOT 1 (975 5825);
DOT 1 (1100 5825);
DOT 1 (-150 6250);
DOT 1 (225 6250);
DOT 1 (600 6250);
DOT 1 (975 6250);
DOT 1 (1375 6250);
DOT 1 (1775 6250);
FORCENOTE
PCMC063T-1R0MN
(-1600 6150) 0;
DISPLAY LEFT (-1600 6150);
DISPLAY 0.808511 (-1600 6150);
FORCENOTE
20220804 CHANGE IC TABLE
(-6775 3550) 0;
DISPLAY LEFT (-6775 3550);
DISPLAY 1.595745 (-6775 3550);
PAINT PINK (-6775 3550);
FORCENOTE
3RD MPS USE 3V3
(-6750 3725) 0;
DISPLAY LEFT (-6750 3725);
DISPLAY 1.170213 (-6750 3725);
PAINT WHITE (-6750 3725);
FORCENOTE
1ST MPS USE 3V3
(-6750 3875) 0;
DISPLAY LEFT (-6750 3875);
DISPLAY 1.170213 (-6750 3875);
PAINT WHITE (-6750 3875);
FORCENOTE
2ND TI USE 5V
(-6750 3800) 0;
DISPLAY LEFT (-6750 3800);
DISPLAY 1.170213 (-6750 3800);
PAINT WHITE (-6750 3800);
FORCENOTE
R TABLE
(-6750 3950) 0;
DISPLAY LEFT (-6750 3950);
DISPLAY 1.170213 (-6750 3950);
PAINT WHITE (-6750 3950);
FORCENOTE
IC TABLE
(-6750 4500) 0;
DISPLAY LEFT (-6750 4500);
DISPLAY 1.170213 (-6750 4500);
PAINT WHITE (-6750 4500);
FORCENOTE
2ND AL051372000
(-6750 4350) 0;
DISPLAY LEFT (-6750 4350);
DISPLAY 1.170213 (-6750 4350);
PAINT WHITE (-6750 4350);
FORCENOTE
1ST AL000682001
(-6750 4425) 0;
DISPLAY LEFT (-6750 4425);
DISPLAY 1.170213 (-6750 4425);
PAINT WHITE (-6750 4425);
FORCENOTE
3RD AL000695001
(-6750 4275) 0;
DISPLAY LEFT (-6750 4275);
DISPLAY 1.170213 (-6750 4275);
PAINT WHITE (-6750 4275);
FORCENOTE
ISAT=22A
(-1600 6050) 0;
DISPLAY LEFT (-1600 6050);
DISPLAY 0.808511 (-1600 6050);
FORCENOTE
DCR=9M OHM
(-1600 6000) 0;
DISPLAY LEFT (-1600 6000);
DISPLAY 0.808511 (-1600 6000);
FORCENOTE
6.5*6.9*3.0
(-1600 6100) 0;
DISPLAY LEFT (-1600 6100);
DISPLAY 0.808511 (-1600 6100);
FORCENOTE
P1V8_PCH_AUX
(-4275 8225) 0;
DISPLAY LEFT (-4275 8225);
DISPLAY 3.936170 (-4275 8225);
PAINT YELLOW (-4275 8225);
FORCENOTE
20220804 UPDATE 2ND FREQ. 
(100 8075) 0;
DISPLAY LEFT (100 8075);
DISPLAY 1.595745 (100 8075);
PAINT PINK (100 8075);
FORCENOTE
20220808 UPDATE PDG REV 1.6
(100 7975) 0;
DISPLAY LEFT (100 7975);
DISPLAY 1.595745 (100 7975);
FORCENOTE
OCP=4A
(-152 8786) 0;
DISPLAY LEFT (-152 8786);
DISPLAY 1.170213 (-152 8786);
PAINT RED (-152 8786);
FORCENOTE
VOUT=1.8V
(-153 9240) 0;
DISPLAY LEFT (-153 9240);
DISPLAY 1.170213 (-153 9240);
PAINT WHITE (-153 9240);
FORCENOTE
TDC=1.6A
(-152 8936) 0;
DISPLAY LEFT (-152 8936);
DISPLAY 1.170213 (-152 8936);
PAINT WHITE (-152 8936);
FORCENOTE
PDG RV 1.6
(-153 8450) 0;
DISPLAY LEFT (-153 8450);
DISPLAY 1.170213 (-153 8450);
PAINT RED (-153 8450);
FORCENOTE
RIPPLE=+/-0.5%
(-153 9090) 0;
DISPLAY LEFT (-153 9090);
DISPLAY 1.170213 (-153 9090);
PAINT WHITE (-153 9090);
FORCENOTE
MAX CURRENT=2.0A
(-152 8861) 0;
DISPLAY LEFT (-152 8861);
DISPLAY 1.170213 (-152 8861);
PAINT WHITE (-152 8861);
FORCENOTE
SLEW RATE=9A/US
(-152 8636) 0;
DISPLAY LEFT (-152 8636);
DISPLAY 1.170213 (-152 8636);
PAINT RED (-152 8636);
FORCENOTE
CURRENT STEP=0.9A
(-152 8711) 0;
DISPLAY LEFT (-152 8711);
DISPLAY 1.170213 (-152 8711);
PAINT WHITE (-152 8711);
FORCENOTE
WORK FREQUENCY=750KHZ
(-152 8566) 0;
DISPLAY LEFT (-152 8566);
DISPLAY 1.170213 (-152 8566);
PAINT WHITE (-152 8566);
FORCENOTE
WORK FREQUENCY=600KHZ
(-175 8200) 0;
DISPLAY LEFT (-175 8200);
DISPLAY 1.170213 (-175 8200);
PAINT WHITE (-175 8200);
FORCENOTE
2ND AL051372000
(-175 8275) 0;
DISPLAY LEFT (-175 8275);
DISPLAY 1.170213 (-175 8275);
PAINT WHITE (-175 8275);
FORCENOTE
DC TOLERANCE=+/-1.7%
(-141 9169) 0;
DISPLAY LEFT (-141 9169);
DISPLAY 1.276596 (-141 9169);
PAINT WHITE (-141 9169);
FORCENOTE
TOTAL TOL=+3.5%~-4% 
(-150 9011) 0;
DISPLAY LEFT (-150 9011);
DISPLAY 1.276596 (-150 9011);
PAINT WHITE (-150 9011);
FORCENOTE
P1V8_PCH_AUX SPECIFICATION
(-153 9390) 0;
DISPLAY LEFT (-153 9390);
DISPLAY 1.468085 (-153 9390);
PAINT WHITE (-153 9390);
QUIT
